(kicad_sch
	(version 20231120)
	(generator "eeschema")
	(generator_version "8.0")
	(paper "A3" portrait)
	(title_block
		(title "Thunderbolt GPU Adapter")
		(date "2024-07-09")
		(rev "1.3.0")
		(company "Antmicro Ltd")
		(comment 1 "www.antmicro.com")
	)
	(junction
		(at 139.7 299.72)
		(diameter 0)
		(color 0 0 0 0)
	)
	(junction
		(at 33.02 287.02)
		(diameter 0)
		(color 0 0 0 0)
	)
	(junction
		(at 111.76 189.23)
		(diameter 0)
		(color 0 0 0 0)
	)
	(junction
		(at 243.84 300.99)
		(diameter 0)
		(color 0 0 0 0)
	)
	(junction
		(at 137.16 99.06)
		(diameter 0)
		(color 0 0 0 0)
	)
	(junction
		(at 243.84 306.07)
		(diameter 0)
		(color 0 0 0 0)
	)
	(junction
		(at 111.76 240.03)
		(diameter 0)
		(color 0 0 0 0)
	)
	(junction
		(at 184.15 298.45)
		(diameter 0)
		(color 0 0 0 0)
	)
	(junction
		(at 111.76 242.57)
		(diameter 0)
		(color 0 0 0 0)
	)
	(junction
		(at 137.16 96.52)
		(diameter 0)
		(color 0 0 0 0)
	)
	(junction
		(at 106.68 374.65)
		(diameter 0)
		(color 0 0 0 0)
	)
	(junction
		(at 243.84 298.45)
		(diameter 0)
		(color 0 0 0 0)
	)
	(junction
		(at 194.31 207.01)
		(diameter 0)
		(color 0 0 0 0)
	)
	(junction
		(at 106.68 358.14)
		(diameter 0)
		(color 0 0 0 0)
	)
	(junction
		(at 111.76 186.69)
		(diameter 0)
		(color 0 0 0 0)
	)
	(junction
		(at 111.76 247.65)
		(diameter 0)
		(color 0 0 0 0)
	)
	(junction
		(at 194.31 214.63)
		(diameter 0)
		(color 0 0 0 0)
	)
	(junction
		(at 184.15 300.99)
		(diameter 0)
		(color 0 0 0 0)
	)
	(junction
		(at 194.31 229.87)
		(diameter 0)
		(color 0 0 0 0)
	)
	(junction
		(at 33.02 281.94)
		(diameter 0)
		(color 0 0 0 0)
	)
	(junction
		(at 46.99 96.52)
		(diameter 0)
		(color 0 0 0 0)
	)
	(junction
		(at 215.9 346.71)
		(diameter 0)
		(color 0 0 0 0)
	)
	(junction
		(at 115.57 284.48)
		(diameter 0)
		(color 0 0 0 0)
	)
	(junction
		(at 113.03 358.14)
		(diameter 0)
		(color 0 0 0 0)
	)
	(junction
		(at 50.8 93.98)
		(diameter 0)
		(color 0 0 0 0)
	)
	(junction
		(at 120.65 384.81)
		(diameter 0)
		(color 0 0 0 0)
	)
	(junction
		(at 194.31 204.47)
		(diameter 0)
		(color 0 0 0 0)
	)
	(junction
		(at 194.31 234.95)
		(diameter 0)
		(color 0 0 0 0)
	)
	(junction
		(at 73.66 382.27)
		(diameter 0)
		(color 0 0 0 0)
	)
	(junction
		(at 194.31 237.49)
		(diameter 0)
		(color 0 0 0 0)
	)
	(junction
		(at 194.31 212.09)
		(diameter 0)
		(color 0 0 0 0)
	)
	(junction
		(at 208.28 232.41)
		(diameter 0)
		(color 0 0 0 0)
	)
	(junction
		(at 139.7 288.29)
		(diameter 0)
		(color 0 0 0 0)
	)
	(junction
		(at 194.31 209.55)
		(diameter 0)
		(color 0 0 0 0)
	)
	(junction
		(at 33.02 284.48)
		(diameter 0)
		(color 0 0 0 0)
	)
	(junction
		(at 137.16 104.14)
		(diameter 0)
		(color 0 0 0 0)
	)
	(junction
		(at 198.12 356.87)
		(diameter 0)
		(color 0 0 0 0)
	)
	(junction
		(at 198.12 368.3)
		(diameter 0)
		(color 0 0 0 0)
	)
	(junction
		(at 194.31 186.69)
		(diameter 0)
		(color 0 0 0 0)
	)
	(junction
		(at 184.15 308.61)
		(diameter 0)
		(color 0 0 0 0)
	)
	(junction
		(at 184.15 306.07)
		(diameter 0)
		(color 0 0 0 0)
	)
	(junction
		(at 73.66 373.38)
		(diameter 0)
		(color 0 0 0 0)
	)
	(no_connect
		(at 123.19 207.01)
	)
	(no_connect
		(at 127 63.5)
	)
	(no_connect
		(at 179.07 161.29)
	)
	(no_connect
		(at 241.3 285.75)
	)
	(no_connect
		(at 179.07 146.05)
	)
	(no_connect
		(at 123.19 214.63)
	)
	(no_connect
		(at 123.19 204.47)
	)
	(no_connect
		(at 241.3 293.37)
	)
	(no_connect
		(at 127 50.8)
	)
	(no_connect
		(at 127 88.9)
	)
	(no_connect
		(at 127 71.12)
	)
	(no_connect
		(at 179.07 151.13)
	)
	(no_connect
		(at 123.19 173.99)
	)
	(no_connect
		(at 179.07 173.99)
	)
	(no_connect
		(at 127 86.36)
	)
	(no_connect
		(at 123.19 196.85)
	)
	(no_connect
		(at 123.19 222.25)
	)
	(no_connect
		(at 123.19 158.75)
	)
	(no_connect
		(at 185.42 283.21)
	)
	(no_connect
		(at 123.19 143.51)
	)
	(no_connect
		(at 123.19 168.91)
	)
	(no_connect
		(at 185.42 280.67)
	)
	(no_connect
		(at 127 78.74)
	)
	(no_connect
		(at 127 58.42)
	)
	(no_connect
		(at 179.07 168.91)
	)
	(no_connect
		(at 123.19 151.13)
	)
	(no_connect
		(at 241.3 288.29)
	)
	(no_connect
		(at 123.19 176.53)
	)
	(no_connect
		(at 179.07 166.37)
	)
	(no_connect
		(at 123.19 166.37)
	)
	(no_connect
		(at 179.07 153.67)
	)
	(no_connect
		(at 127 48.26)
	)
	(no_connect
		(at 123.19 212.09)
	)
	(no_connect
		(at 123.19 153.67)
	)
	(no_connect
		(at 123.19 219.71)
	)
	(no_connect
		(at 127 55.88)
	)
	(no_connect
		(at 179.07 158.75)
	)
	(no_connect
		(at 123.19 229.87)
	)
	(no_connect
		(at 123.19 227.33)
	)
	(no_connect
		(at 179.07 176.53)
	)
	(no_connect
		(at 179.07 143.51)
	)
	(no_connect
		(at 123.19 161.29)
	)
	(no_connect
		(at 127 81.28)
	)
	(no_connect
		(at 127 73.66)
	)
	(no_connect
		(at 123.19 146.05)
	)
	(no_connect
		(at 127 66.04)
	)
	(no_connect
		(at 123.19 199.39)
	)
	(no_connect
		(at 185.42 288.29)
	)
	(wire
		(pts
			(xy 137.16 93.98) (xy 137.16 96.52)
		)
		(stroke
			(width 0)
			(type default)
		)
	)
	(wire
		(pts
			(xy 248.92 76.2) (xy 262.89 76.2)
		)
		(stroke
			(width 0)
			(type default)
		)
	)
	(wire
		(pts
			(xy 179.07 204.47) (xy 182.88 204.47)
		)
		(stroke
			(width 0)
			(type default)
		)
	)
	(wire
		(pts
			(xy 248.92 83.82) (xy 262.89 83.82)
		)
		(stroke
			(width 0)
			(type default)
		)
	)
	(wire
		(pts
			(xy 73.66 373.38) (xy 73.66 370.84)
		)
		(stroke
			(width 0)
			(type default)
		)
	)
	(wire
		(pts
			(xy 243.84 300.99) (xy 243.84 306.07)
		)
		(stroke
			(width 0)
			(type default)
		)
	)
	(wire
		(pts
			(xy 179.07 237.49) (xy 182.88 237.49)
		)
		(stroke
			(width 0)
			(type default)
		)
	)
	(wire
		(pts
			(xy 73.66 382.27) (xy 73.66 384.81)
		)
		(stroke
			(width 0)
			(type default)
		)
	)
	(wire
		(pts
			(xy 248.92 60.96) (xy 262.89 60.96)
		)
		(stroke
			(width 0)
			(type default)
		)
	)
	(wire
		(pts
			(xy 179.07 207.01) (xy 182.88 207.01)
		)
		(stroke
			(width 0)
			(type default)
		)
	)
	(wire
		(pts
			(xy 137.16 104.14) (xy 137.16 105.41)
		)
		(stroke
			(width 0)
			(type default)
		)
	)
	(wire
		(pts
			(xy 179.07 201.93) (xy 182.88 201.93)
		)
		(stroke
			(width 0)
			(type default)
		)
	)
	(wire
		(pts
			(xy 31.75 281.94) (xy 33.02 281.94)
		)
		(stroke
			(width 0)
			(type default)
		)
	)
	(wire
		(pts
			(xy 31.75 379.73) (xy 45.72 379.73)
		)
		(stroke
			(width 0)
			(type default)
		)
	)
	(wire
		(pts
			(xy 49.53 73.66) (xy 71.12 73.66)
		)
		(stroke
			(width 0)
			(type default)
		)
	)
	(wire
		(pts
			(xy 194.31 209.55) (xy 194.31 207.01)
		)
		(stroke
			(width 0)
			(type default)
		)
	)
	(wire
		(pts
			(xy 187.96 237.49) (xy 194.31 237.49)
		)
		(stroke
			(width 0)
			(type default)
		)
	)
	(wire
		(pts
			(xy 248.92 68.58) (xy 262.89 68.58)
		)
		(stroke
			(width 0)
			(type default)
		)
	)
	(wire
		(pts
			(xy 31.75 377.19) (xy 45.72 377.19)
		)
		(stroke
			(width 0)
			(type default)
		)
	)
	(wire
		(pts
			(xy 119.38 247.65) (xy 123.19 247.65)
		)
		(stroke
			(width 0)
			(type default)
		)
	)
	(wire
		(pts
			(xy 109.22 302.26) (xy 100.33 302.26)
		)
		(stroke
			(width 0)
			(type default)
		)
	)
	(wire
		(pts
			(xy 179.07 214.63) (xy 182.88 214.63)
		)
		(stroke
			(width 0)
			(type default)
		)
	)
	(wire
		(pts
			(xy 115.57 284.48) (xy 115.57 285.75)
		)
		(stroke
			(width 0)
			(type default)
		)
	)
	(wire
		(pts
			(xy 184.15 298.45) (xy 185.42 298.45)
		)
		(stroke
			(width 0)
			(type default)
		)
	)
	(wire
		(pts
			(xy 146.05 293.37) (xy 144.78 293.37)
		)
		(stroke
			(width 0)
			(type default)
		)
	)
	(wire
		(pts
			(xy 179.07 209.55) (xy 182.88 209.55)
		)
		(stroke
			(width 0)
			(type default)
		)
	)
	(wire
		(pts
			(xy 120.65 358.14) (xy 120.65 360.68)
		)
		(stroke
			(width 0)
			(type default)
		)
	)
	(wire
		(pts
			(xy 157.48 60.96) (xy 173.99 60.96)
		)
		(stroke
			(width 0)
			(type default)
		)
	)
	(wire
		(pts
			(xy 184.15 293.37) (xy 185.42 293.37)
		)
		(stroke
			(width 0)
			(type default)
		)
	)
	(wire
		(pts
			(xy 106.68 358.14) (xy 106.68 356.87)
		)
		(stroke
			(width 0)
			(type default)
		)
	)
	(wire
		(pts
			(xy 101.6 382.27) (xy 133.35 382.27)
		)
		(stroke
			(width 0)
			(type default)
		)
	)
	(wire
		(pts
			(xy 194.31 215.9) (xy 194.31 214.63)
		)
		(stroke
			(width 0)
			(type default)
		)
	)
	(wire
		(pts
			(xy 119.38 186.69) (xy 123.19 186.69)
		)
		(stroke
			(width 0)
			(type default)
		)
	)
	(wire
		(pts
			(xy 255.27 73.66) (xy 262.89 73.66)
		)
		(stroke
			(width 0)
			(type default)
		)
	)
	(wire
		(pts
			(xy 38.1 353.06) (xy 39.37 353.06)
		)
		(stroke
			(width 0)
			(type default)
		)
	)
	(wire
		(pts
			(xy 255.27 66.04) (xy 262.89 66.04)
		)
		(stroke
			(width 0)
			(type default)
		)
	)
	(wire
		(pts
			(xy 147.32 288.29) (xy 149.86 288.29)
		)
		(stroke
			(width 0)
			(type default)
		)
	)
	(wire
		(pts
			(xy 120.65 384.81) (xy 133.35 384.81)
		)
		(stroke
			(width 0)
			(type default)
		)
	)
	(wire
		(pts
			(xy 111.76 181.61) (xy 114.3 181.61)
		)
		(stroke
			(width 0)
			(type default)
		)
	)
	(wire
		(pts
			(xy 113.03 365.76) (xy 113.03 377.19)
		)
		(stroke
			(width 0)
			(type default)
		)
	)
	(wire
		(pts
			(xy 100.33 284.48) (xy 104.14 284.48)
		)
		(stroke
			(width 0)
			(type default)
		)
	)
	(wire
		(pts
			(xy 187.96 356.87) (xy 190.5 356.87)
		)
		(stroke
			(width 0)
			(type default)
		)
	)
	(wire
		(pts
			(xy 111.76 248.92) (xy 111.76 247.65)
		)
		(stroke
			(width 0)
			(type default)
		)
	)
	(wire
		(pts
			(xy 59.69 58.42) (xy 71.12 58.42)
		)
		(stroke
			(width 0)
			(type default)
		)
	)
	(wire
		(pts
			(xy 194.31 187.96) (xy 194.31 186.69)
		)
		(stroke
			(width 0)
			(type default)
		)
	)
	(wire
		(pts
			(xy 184.15 293.37) (xy 184.15 298.45)
		)
		(stroke
			(width 0)
			(type default)
		)
	)
	(wire
		(pts
			(xy 229.87 81.28) (xy 250.19 81.28)
		)
		(stroke
			(width 0)
			(type default)
		)
	)
	(wire
		(pts
			(xy 194.31 214.63) (xy 194.31 212.09)
		)
		(stroke
			(width 0)
			(type default)
		)
	)
	(wire
		(pts
			(xy 27.94 73.66) (xy 44.45 73.66)
		)
		(stroke
			(width 0)
			(type default)
		)
	)
	(wire
		(pts
			(xy 44.45 78.74) (xy 71.12 78.74)
		)
		(stroke
			(width 0)
			(type default)
		)
	)
	(wire
		(pts
			(xy 101.6 372.11) (xy 133.35 372.11)
		)
		(stroke
			(width 0)
			(type default)
		)
	)
	(wire
		(pts
			(xy 40.64 287.02) (xy 44.45 287.02)
		)
		(stroke
			(width 0)
			(type default)
		)
	)
	(wire
		(pts
			(xy 213.36 356.87) (xy 213.36 360.68)
		)
		(stroke
			(width 0)
			(type default)
		)
	)
	(wire
		(pts
			(xy 170.18 96.52) (xy 173.99 96.52)
		)
		(stroke
			(width 0)
			(type default)
		)
	)
	(wire
		(pts
			(xy 44.45 63.5) (xy 71.12 63.5)
		)
		(stroke
			(width 0)
			(type default)
		)
	)
	(wire
		(pts
			(xy 35.56 93.98) (xy 50.8 93.98)
		)
		(stroke
			(width 0)
			(type default)
		)
	)
	(wire
		(pts
			(xy 179.07 194.31) (xy 187.96 194.31)
		)
		(stroke
			(width 0)
			(type default)
		)
	)
	(wire
		(pts
			(xy 173.99 88.9) (xy 157.48 88.9)
		)
		(stroke
			(width 0)
			(type default)
		)
	)
	(wire
		(pts
			(xy 106.68 358.14) (xy 106.68 360.68)
		)
		(stroke
			(width 0)
			(type default)
		)
	)
	(wire
		(pts
			(xy 46.99 96.52) (xy 46.99 100.33)
		)
		(stroke
			(width 0)
			(type default)
		)
	)
	(wire
		(pts
			(xy 41.91 294.64) (xy 41.91 298.45)
		)
		(stroke
			(width 0)
			(type default)
		)
	)
	(wire
		(pts
			(xy 157.48 81.28) (xy 173.99 81.28)
		)
		(stroke
			(width 0)
			(type default)
		)
	)
	(wire
		(pts
			(xy 119.38 234.95) (xy 123.19 234.95)
		)
		(stroke
			(width 0)
			(type default)
		)
	)
	(wire
		(pts
			(xy 194.31 237.49) (xy 194.31 238.76)
		)
		(stroke
			(width 0)
			(type default)
		)
	)
	(wire
		(pts
			(xy 184.15 300.99) (xy 184.15 306.07)
		)
		(stroke
			(width 0)
			(type default)
		)
	)
	(wire
		(pts
			(xy 179.07 229.87) (xy 182.88 229.87)
		)
		(stroke
			(width 0)
			(type default)
		)
	)
	(wire
		(pts
			(xy 109.22 281.94) (xy 115.57 281.94)
		)
		(stroke
			(width 0)
			(type default)
		)
	)
	(wire
		(pts
			(xy 73.66 382.27) (xy 76.2 382.27)
		)
		(stroke
			(width 0)
			(type default)
		)
	)
	(wire
		(pts
			(xy 157.48 83.82) (xy 173.99 83.82)
		)
		(stroke
			(width 0)
			(type default)
		)
	)
	(wire
		(pts
			(xy 127 96.52) (xy 129.54 96.52)
		)
		(stroke
			(width 0)
			(type default)
		)
	)
	(wire
		(pts
			(xy 100.33 299.72) (xy 109.22 299.72)
		)
		(stroke
			(width 0)
			(type default)
		)
	)
	(wire
		(pts
			(xy 31.75 382.27) (xy 45.72 382.27)
		)
		(stroke
			(width 0)
			(type default)
		)
	)
	(wire
		(pts
			(xy 243.84 306.07) (xy 243.84 308.61)
		)
		(stroke
			(width 0)
			(type default)
		)
	)
	(wire
		(pts
			(xy 127 99.06) (xy 129.54 99.06)
		)
		(stroke
			(width 0)
			(type default)
		)
	)
	(wire
		(pts
			(xy 229.87 60.96) (xy 243.84 60.96)
		)
		(stroke
			(width 0)
			(type default)
		)
	)
	(wire
		(pts
			(xy 179.07 199.39) (xy 187.96 199.39)
		)
		(stroke
			(width 0)
			(type default)
		)
	)
	(wire
		(pts
			(xy 46.99 105.41) (xy 46.99 107.95)
		)
		(stroke
			(width 0)
			(type default)
		)
	)
	(wire
		(pts
			(xy 241.3 280.67) (xy 243.84 280.67)
		)
		(stroke
			(width 0)
			(type default)
		)
	)
	(wire
		(pts
			(xy 157.48 76.2) (xy 173.99 76.2)
		)
		(stroke
			(width 0)
			(type default)
		)
	)
	(wire
		(pts
			(xy 187.96 212.09) (xy 194.31 212.09)
		)
		(stroke
			(width 0)
			(type default)
		)
	)
	(wire
		(pts
			(xy 68.58 104.14) (xy 71.12 104.14)
		)
		(stroke
			(width 0)
			(type default)
		)
	)
	(wire
		(pts
			(xy 187.96 224.79) (xy 193.04 224.79)
		)
		(stroke
			(width 0)
			(type default)
		)
	)
	(wire
		(pts
			(xy 33.02 289.56) (xy 35.56 289.56)
		)
		(stroke
			(width 0)
			(type default)
		)
	)
	(wire
		(pts
			(xy 59.69 50.8) (xy 71.12 50.8)
		)
		(stroke
			(width 0)
			(type default)
		)
	)
	(wire
		(pts
			(xy 111.76 186.69) (xy 111.76 181.61)
		)
		(stroke
			(width 0)
			(type default)
		)
	)
	(wire
		(pts
			(xy 119.38 242.57) (xy 123.19 242.57)
		)
		(stroke
			(width 0)
			(type default)
		)
	)
	(wire
		(pts
			(xy 100.33 281.94) (xy 104.14 281.94)
		)
		(stroke
			(width 0)
			(type default)
		)
	)
	(wire
		(pts
			(xy 215.9 346.71) (xy 215.9 347.98)
		)
		(stroke
			(width 0)
			(type default)
		)
	)
	(wire
		(pts
			(xy 111.76 234.95) (xy 114.3 234.95)
		)
		(stroke
			(width 0)
			(type default)
		)
	)
	(wire
		(pts
			(xy 111.76 189.23) (xy 111.76 186.69)
		)
		(stroke
			(width 0)
			(type default)
		)
	)
	(wire
		(pts
			(xy 232.41 91.44) (xy 229.87 91.44)
		)
		(stroke
			(width 0)
			(type default)
		)
	)
	(wire
		(pts
			(xy 119.38 189.23) (xy 123.19 189.23)
		)
		(stroke
			(width 0)
			(type default)
		)
	)
	(wire
		(pts
			(xy 198.12 368.3) (xy 213.36 368.3)
		)
		(stroke
			(width 0)
			(type default)
		)
	)
	(wire
		(pts
			(xy 44.45 71.12) (xy 71.12 71.12)
		)
		(stroke
			(width 0)
			(type default)
		)
	)
	(wire
		(pts
			(xy 134.62 96.52) (xy 137.16 96.52)
		)
		(stroke
			(width 0)
			(type default)
		)
	)
	(wire
		(pts
			(xy 187.96 229.87) (xy 194.31 229.87)
		)
		(stroke
			(width 0)
			(type default)
		)
	)
	(wire
		(pts
			(xy 243.84 280.67) (xy 243.84 298.45)
		)
		(stroke
			(width 0)
			(type default)
		)
	)
	(wire
		(pts
			(xy 229.87 68.58) (xy 243.84 68.58)
		)
		(stroke
			(width 0)
			(type default)
		)
	)
	(wire
		(pts
			(xy 33.02 284.48) (xy 33.02 281.94)
		)
		(stroke
			(width 0)
			(type default)
		)
	)
	(wire
		(pts
			(xy 194.31 229.87) (xy 194.31 234.95)
		)
		(stroke
			(width 0)
			(type default)
		)
	)
	(wire
		(pts
			(xy 50.8 93.98) (xy 50.8 100.33)
		)
		(stroke
			(width 0)
			(type default)
		)
	)
	(wire
		(pts
			(xy 27.94 71.12) (xy 39.37 71.12)
		)
		(stroke
			(width 0)
			(type default)
		)
	)
	(wire
		(pts
			(xy 33.02 287.02) (xy 33.02 284.48)
		)
		(stroke
			(width 0)
			(type default)
		)
	)
	(wire
		(pts
			(xy 100.33 287.02) (xy 101.6 287.02)
		)
		(stroke
			(width 0)
			(type default)
		)
	)
	(wire
		(pts
			(xy 173.99 91.44) (xy 157.48 91.44)
		)
		(stroke
			(width 0)
			(type default)
		)
	)
	(wire
		(pts
			(xy 71.12 373.38) (xy 73.66 373.38)
		)
		(stroke
			(width 0)
			(type default)
		)
	)
	(wire
		(pts
			(xy 157.48 68.58) (xy 173.99 68.58)
		)
		(stroke
			(width 0)
			(type default)
		)
	)
	(wire
		(pts
			(xy 124.46 299.72) (xy 139.7 299.72)
		)
		(stroke
			(width 0)
			(type default)
		)
	)
	(wire
		(pts
			(xy 187.96 186.69) (xy 194.31 186.69)
		)
		(stroke
			(width 0)
			(type default)
		)
	)
	(wire
		(pts
			(xy 179.07 196.85) (xy 187.96 196.85)
		)
		(stroke
			(width 0)
			(type default)
		)
	)
	(wire
		(pts
			(xy 124.46 294.64) (xy 124.46 299.72)
		)
		(stroke
			(width 0)
			(type default)
		)
	)
	(wire
		(pts
			(xy 187.96 368.3) (xy 190.5 368.3)
		)
		(stroke
			(width 0)
			(type default)
		)
	)
	(wire
		(pts
			(xy 220.98 346.71) (xy 220.98 358.14)
		)
		(stroke
			(width 0)
			(type default)
		)
	)
	(wire
		(pts
			(xy 255.27 58.42) (xy 262.89 58.42)
		)
		(stroke
			(width 0)
			(type default)
		)
	)
	(wire
		(pts
			(xy 213.36 363.22) (xy 222.25 363.22)
		)
		(stroke
			(width 0)
			(type default)
		)
	)
	(wire
		(pts
			(xy 229.87 66.04) (xy 250.19 66.04)
		)
		(stroke
			(width 0)
			(type default)
		)
	)
	(wire
		(pts
			(xy 184.15 298.45) (xy 184.15 300.99)
		)
		(stroke
			(width 0)
			(type default)
		)
	)
	(wire
		(pts
			(xy 57.15 86.36) (xy 71.12 86.36)
		)
		(stroke
			(width 0)
			(type default)
		)
	)
	(wire
		(pts
			(xy 246.38 358.14) (xy 262.89 358.14)
		)
		(stroke
			(width 0)
			(type default)
		)
	)
	(wire
		(pts
			(xy 113.03 358.14) (xy 113.03 360.68)
		)
		(stroke
			(width 0)
			(type default)
		)
	)
	(wire
		(pts
			(xy 101.6 384.81) (xy 120.65 384.81)
		)
		(stroke
			(width 0)
			(type default)
		)
	)
	(wire
		(pts
			(xy 111.76 247.65) (xy 114.3 247.65)
		)
		(stroke
			(width 0)
			(type default)
		)
	)
	(wire
		(pts
			(xy 184.15 306.07) (xy 185.42 306.07)
		)
		(stroke
			(width 0)
			(type default)
		)
	)
	(wire
		(pts
			(xy 187.96 204.47) (xy 194.31 204.47)
		)
		(stroke
			(width 0)
			(type default)
		)
	)
	(wire
		(pts
			(xy 27.94 81.28) (xy 44.45 81.28)
		)
		(stroke
			(width 0)
			(type default)
		)
	)
	(wire
		(pts
			(xy 33.02 289.56) (xy 33.02 287.02)
		)
		(stroke
			(width 0)
			(type default)
		)
	)
	(wire
		(pts
			(xy 134.62 104.14) (xy 137.16 104.14)
		)
		(stroke
			(width 0)
			(type default)
		)
	)
	(wire
		(pts
			(xy 27.94 66.04) (xy 44.45 66.04)
		)
		(stroke
			(width 0)
			(type default)
		)
	)
	(wire
		(pts
			(xy 184.15 308.61) (xy 184.15 311.15)
		)
		(stroke
			(width 0)
			(type default)
		)
	)
	(wire
		(pts
			(xy 106.68 365.76) (xy 106.68 374.65)
		)
		(stroke
			(width 0)
			(type default)
		)
	)
	(wire
		(pts
			(xy 59.69 48.26) (xy 71.12 48.26)
		)
		(stroke
			(width 0)
			(type default)
		)
	)
	(wire
		(pts
			(xy 137.16 96.52) (xy 137.16 99.06)
		)
		(stroke
			(width 0)
			(type default)
		)
	)
	(wire
		(pts
			(xy 109.22 307.34) (xy 100.33 307.34)
		)
		(stroke
			(width 0)
			(type default)
		)
	)
	(wire
		(pts
			(xy 187.96 214.63) (xy 194.31 214.63)
		)
		(stroke
			(width 0)
			(type default)
		)
	)
	(wire
		(pts
			(xy 222.25 358.14) (xy 220.98 358.14)
		)
		(stroke
			(width 0)
			(type default)
		)
	)
	(wire
		(pts
			(xy 31.75 384.81) (xy 45.72 384.81)
		)
		(stroke
			(width 0)
			(type default)
		)
	)
	(wire
		(pts
			(xy 100.33 294.64) (xy 124.46 294.64)
		)
		(stroke
			(width 0)
			(type default)
		)
	)
	(wire
		(pts
			(xy 39.37 353.06) (xy 39.37 354.33)
		)
		(stroke
			(width 0)
			(type default)
		)
	)
	(wire
		(pts
			(xy 241.3 298.45) (xy 243.84 298.45)
		)
		(stroke
			(width 0)
			(type default)
		)
	)
	(wire
		(pts
			(xy 241.3 306.07) (xy 243.84 306.07)
		)
		(stroke
			(width 0)
			(type default)
		)
	)
	(polyline
		(pts
			(xy 149.86 335.28) (xy 149.86 407.67)
		)
		(stroke
			(width 0)
			(type default)
		)
	)
	(wire
		(pts
			(xy 238.76 96.52) (xy 241.3 96.52)
		)
		(stroke
			(width 0)
			(type default)
		)
	)
	(wire
		(pts
			(xy 194.31 227.33) (xy 194.31 229.87)
		)
		(stroke
			(width 0)
			(type default)
		)
	)
	(wire
		(pts
			(xy 49.53 81.28) (xy 71.12 81.28)
		)
		(stroke
			(width 0)
			(type default)
		)
	)
	(wire
		(pts
			(xy 157.48 73.66) (xy 173.99 73.66)
		)
		(stroke
			(width 0)
			(type default)
		)
	)
	(wire
		(pts
			(xy 137.16 99.06) (xy 137.16 104.14)
		)
		(stroke
			(width 0)
			(type default)
		)
	)
	(wire
		(pts
			(xy 229.87 73.66) (xy 250.19 73.66)
		)
		(stroke
			(width 0)
			(type default)
		)
	)
	(wire
		(pts
			(xy 246.38 363.22) (xy 262.89 363.22)
		)
		(stroke
			(width 0)
			(type default)
		)
	)
	(wire
		(pts
			(xy 100.33 292.1) (xy 124.46 292.1)
		)
		(stroke
			(width 0)
			(type default)
		)
	)
	(wire
		(pts
			(xy 229.87 76.2) (xy 243.84 76.2)
		)
		(stroke
			(width 0)
			(type default)
		)
	)
	(wire
		(pts
			(xy 101.6 377.19) (xy 113.03 377.19)
		)
		(stroke
			(width 0)
			(type default)
		)
	)
	(wire
		(pts
			(xy 27.94 63.5) (xy 39.37 63.5)
		)
		(stroke
			(width 0)
			(type default)
		)
	)
	(wire
		(pts
			(xy 194.31 186.69) (xy 194.31 181.61)
		)
		(stroke
			(width 0)
			(type default)
		)
	)
	(wire
		(pts
			(xy 115.57 281.94) (xy 115.57 284.48)
		)
		(stroke
			(width 0)
			(type default)
		)
	)
	(wire
		(pts
			(xy 111.76 186.69) (xy 114.3 186.69)
		)
		(stroke
			(width 0)
			(type default)
		)
	)
	(wire
		(pts
			(xy 31.75 372.11) (xy 45.72 372.11)
		)
		(stroke
			(width 0)
			(type default)
		)
	)
	(wire
		(pts
			(xy 39.37 359.41) (xy 39.37 360.68)
		)
		(stroke
			(width 0)
			(type default)
		)
	)
	(wire
		(pts
			(xy 162.56 96.52) (xy 165.1 96.52)
		)
		(stroke
			(width 0)
			(type default)
		)
	)
	(wire
		(pts
			(xy 212.09 346.71) (xy 215.9 346.71)
		)
		(stroke
			(width 0)
			(type default)
		)
	)
	(wire
		(pts
			(xy 208.28 232.41) (xy 210.82 232.41)
		)
		(stroke
			(width 0)
			(type default)
		)
	)
	(wire
		(pts
			(xy 124.46 292.1) (xy 124.46 288.29)
		)
		(stroke
			(width 0)
			(type default)
		)
	)
	(wire
		(pts
			(xy 191.77 361.95) (xy 193.04 361.95)
		)
		(stroke
			(width 0)
			(type default)
		)
	)
	(wire
		(pts
			(xy 187.96 234.95) (xy 194.31 234.95)
		)
		(stroke
			(width 0)
			(type default)
		)
	)
	(wire
		(pts
			(xy 241.3 300.99) (xy 243.84 300.99)
		)
		(stroke
			(width 0)
			(type default)
		)
	)
	(wire
		(pts
			(xy 195.58 356.87) (xy 198.12 356.87)
		)
		(stroke
			(width 0)
			(type default)
		)
	)
	(wire
		(pts
			(xy 73.66 373.38) (xy 76.2 373.38)
		)
		(stroke
			(width 0)
			(type default)
		)
	)
	(wire
		(pts
			(xy 184.15 308.61) (xy 185.42 308.61)
		)
		(stroke
			(width 0)
			(type default)
		)
	)
	(wire
		(pts
			(xy 179.07 234.95) (xy 182.88 234.95)
		)
		(stroke
			(width 0)
			(type default)
		)
	)
	(wire
		(pts
			(xy 157.48 58.42) (xy 173.99 58.42)
		)
		(stroke
			(width 0)
			(type default)
		)
	)
	(wire
		(pts
			(xy 194.31 204.47) (xy 194.31 201.93)
		)
		(stroke
			(width 0)
			(type default)
		)
	)
	(wire
		(pts
			(xy 213.36 368.3) (xy 213.36 363.22)
		)
		(stroke
			(width 0)
			(type default)
		)
	)
	(wire
		(pts
			(xy 241.3 96.52) (xy 241.3 97.79)
		)
		(stroke
			(width 0)
			(type default)
		)
	)
	(wire
		(pts
			(xy 179.07 181.61) (xy 182.88 181.61)
		)
		(stroke
			(width 0)
			(type default)
		)
	)
	(wire
		(pts
			(xy 46.99 96.52) (xy 71.12 96.52)
		)
		(stroke
			(width 0)
			(type default)
		)
	)
	(wire
		(pts
			(xy 101.6 379.73) (xy 124.46 379.73)
		)
		(stroke
			(width 0)
			(type default)
		)
	)
	(wire
		(pts
			(xy 111.76 242.57) (xy 114.3 242.57)
		)
		(stroke
			(width 0)
			(type default)
		)
	)
	(wire
		(pts
			(xy 139.7 297.18) (xy 139.7 299.72)
		)
		(stroke
			(width 0)
			(type default)
		)
	)
	(wire
		(pts
			(xy 213.36 360.68) (xy 222.25 360.68)
		)
		(stroke
			(width 0)
			(type default)
		)
	)
	(wire
		(pts
			(xy 139.7 288.29) (xy 142.24 288.29)
		)
		(stroke
			(width 0)
			(type default)
		)
	)
	(wire
		(pts
			(xy 120.65 365.76) (xy 120.65 384.81)
		)
		(stroke
			(width 0)
			(type default)
		)
	)
	(wire
		(pts
			(xy 134.62 99.06) (xy 137.16 99.06)
		)
		(stroke
			(width 0)
			(type default)
		)
	)
	(wire
		(pts
			(xy 106.68 374.65) (xy 133.35 374.65)
		)
		(stroke
			(width 0)
			(type default)
		)
	)
	(wire
		(pts
			(xy 41.91 307.34) (xy 44.45 307.34)
		)
		(stroke
			(width 0)
			(type default)
		)
	)
	(wire
		(pts
			(xy 179.07 224.79) (xy 182.88 224.79)
		)
		(stroke
			(width 0)
			(type default)
		)
	)
	(wire
		(pts
			(xy 195.58 368.3) (xy 198.12 368.3)
		)
		(stroke
			(width 0)
			(type default)
		)
	)
	(wire
		(pts
			(xy 215.9 346.71) (xy 220.98 346.71)
		)
		(stroke
			(width 0)
			(type default)
		)
	)
	(wire
		(pts
			(xy 71.12 382.27) (xy 73.66 382.27)
		)
		(stroke
			(width 0)
			(type default)
		)
	)
	(wire
		(pts
			(xy 109.22 304.8) (xy 100.33 304.8)
		)
		(stroke
			(width 0)
			(type default)
		)
	)
	(wire
		(pts
			(xy 119.38 240.03) (xy 123.19 240.03)
		)
		(stroke
			(width 0)
			(type default)
		)
	)
	(wire
		(pts
			(xy 208.28 228.6) (xy 208.28 232.41)
		)
		(stroke
			(width 0)
			(type default)
		)
	)
	(wire
		(pts
			(xy 179.07 222.25) (xy 193.04 222.25)
		)
		(stroke
			(width 0)
			(type default)
		)
	)
	(wire
		(pts
			(xy 187.96 181.61) (xy 194.31 181.61)
		)
		(stroke
			(width 0)
			(type default)
		)
	)
	(wire
		(pts
			(xy 50.8 105.41) (xy 50.8 107.95)
		)
		(stroke
			(width 0)
			(type default)
		)
	)
	(wire
		(pts
			(xy 41.91 303.53) (xy 41.91 307.34)
		)
		(stroke
			(width 0)
			(type default)
		)
	)
	(wire
		(pts
			(xy 198.12 365.76) (xy 198.12 368.3)
		)
		(stroke
			(width 0)
			(type default)
		)
	)
	(wire
		(pts
			(xy 119.38 181.61) (xy 123.19 181.61)
		)
		(stroke
			(width 0)
			(type default)
		)
	)
	(wire
		(pts
			(xy 139.7 299.72) (xy 142.24 299.72)
		)
		(stroke
			(width 0)
			(type default)
		)
	)
	(polyline
		(pts
			(xy 12.7 335.28) (xy 285.75 335.28)
		)
		(stroke
			(width 0)
			(type default)
		)
	)
	(wire
		(pts
			(xy 49.53 66.04) (xy 71.12 66.04)
		)
		(stroke
			(width 0)
			(type default)
		)
	)
	(wire
		(pts
			(xy 179.07 186.69) (xy 182.88 186.69)
		)
		(stroke
			(width 0)
			(type default)
		)
	)
	(wire
		(pts
			(xy 111.76 242.57) (xy 111.76 240.03)
		)
		(stroke
			(width 0)
			(type default)
		)
	)
	(wire
		(pts
			(xy 179.07 232.41) (xy 208.28 232.41)
		)
		(stroke
			(width 0)
			(type default)
		)
	)
	(wire
		(pts
			(xy 157.48 66.04) (xy 173.99 66.04)
		)
		(stroke
			(width 0)
			(type default)
		)
	)
	(wire
		(pts
			(xy 33.02 287.02) (xy 35.56 287.02)
		)
		(stroke
			(width 0)
			(type default)
		)
	)
	(wire
		(pts
			(xy 246.38 365.76) (xy 262.89 365.76)
		)
		(stroke
			(width 0)
			(type default)
		)
	)
	(wire
		(pts
			(xy 129.54 379.73) (xy 133.35 379.73)
		)
		(stroke
			(width 0)
			(type default)
		)
	)
	(wire
		(pts
			(xy 194.31 207.01) (xy 194.31 204.47)
		)
		(stroke
			(width 0)
			(type default)
		)
	)
	(wire
		(pts
			(xy 27.94 78.74) (xy 39.37 78.74)
		)
		(stroke
			(width 0)
			(type default)
		)
	)
	(wire
		(pts
			(xy 198.12 356.87) (xy 213.36 356.87)
		)
		(stroke
			(width 0)
			(type default)
		)
	)
	(wire
		(pts
			(xy 60.96 104.14) (xy 63.5 104.14)
		)
		(stroke
			(width 0)
			(type default)
		)
	)
	(wire
		(pts
			(xy 35.56 96.52) (xy 46.99 96.52)
		)
		(stroke
			(width 0)
			(type default)
		)
	)
	(wire
		(pts
			(xy 229.87 58.42) (xy 250.19 58.42)
		)
		(stroke
			(width 0)
			(type default)
		)
	)
	(wire
		(pts
			(xy 67.31 99.06) (xy 71.12 99.06)
		)
		(stroke
			(width 0)
			(type default)
		)
	)
	(wire
		(pts
			(xy 198.12 358.14) (xy 198.12 356.87)
		)
		(stroke
			(width 0)
			(type default)
		)
	)
	(wire
		(pts
			(xy 57.15 88.9) (xy 71.12 88.9)
		)
		(stroke
			(width 0)
			(type default)
		)
	)
	(wire
		(pts
			(xy 184.15 300.99) (xy 185.42 300.99)
		)
		(stroke
			(width 0)
			(type default)
		)
	)
	(wire
		(pts
			(xy 111.76 234.95) (xy 111.76 240.03)
		)
		(stroke
			(width 0)
			(type default)
		)
	)
	(wire
		(pts
			(xy 33.02 284.48) (xy 35.56 284.48)
		)
		(stroke
			(width 0)
			(type default)
		)
	)
	(wire
		(pts
			(xy 194.31 234.95) (xy 194.31 237.49)
		)
		(stroke
			(width 0)
			(type default)
		)
	)
	(wire
		(pts
			(xy 113.03 358.14) (xy 120.65 358.14)
		)
		(stroke
			(width 0)
			(type default)
		)
	)
	(wire
		(pts
			(xy 31.75 374.65) (xy 45.72 374.65)
		)
		(stroke
			(width 0)
			(type default)
		)
	)
	(wire
		(pts
			(xy 127 104.14) (xy 129.54 104.14)
		)
		(stroke
			(width 0)
			(type default)
		)
	)
	(wire
		(pts
			(xy 187.96 209.55) (xy 194.31 209.55)
		)
		(stroke
			(width 0)
			(type default)
		)
	)
	(wire
		(pts
			(xy 243.84 298.45) (xy 243.84 300.99)
		)
		(stroke
			(width 0)
			(type default)
		)
	)
	(wire
		(pts
			(xy 59.69 55.88) (xy 71.12 55.88)
		)
		(stroke
			(width 0)
			(type default)
		)
	)
	(wire
		(pts
			(xy 187.96 201.93) (xy 194.31 201.93)
		)
		(stroke
			(width 0)
			(type default)
		)
	)
	(wire
		(pts
			(xy 40.64 284.48) (xy 44.45 284.48)
		)
		(stroke
			(width 0)
			(type default)
		)
	)
	(wire
		(pts
			(xy 60.96 105.41) (xy 60.96 104.14)
		)
		(stroke
			(width 0)
			(type default)
		)
	)
	(wire
		(pts
			(xy 40.64 289.56) (xy 44.45 289.56)
		)
		(stroke
			(width 0)
			(type default)
		)
	)
	(wire
		(pts
			(xy 111.76 247.65) (xy 111.76 242.57)
		)
		(stroke
			(width 0)
			(type default)
		)
	)
	(wire
		(pts
			(xy 124.46 288.29) (xy 139.7 288.29)
		)
		(stroke
			(width 0)
			(type default)
		)
	)
	(wire
		(pts
			(xy 33.02 281.94) (xy 35.56 281.94)
		)
		(stroke
			(width 0)
			(type default)
		)
	)
	(wire
		(pts
			(xy 111.76 189.23) (xy 114.3 189.23)
		)
		(stroke
			(width 0)
			(type default)
		)
	)
	(wire
		(pts
			(xy 106.68 358.14) (xy 113.03 358.14)
		)
		(stroke
			(width 0)
			(type default)
		)
	)
	(wire
		(pts
			(xy 111.76 240.03) (xy 114.3 240.03)
		)
		(stroke
			(width 0)
			(type default)
		)
	)
	(wire
		(pts
			(xy 147.32 299.72) (xy 149.86 299.72)
		)
		(stroke
			(width 0)
			(type default)
		)
	)
	(wire
		(pts
			(xy 246.38 360.68) (xy 262.89 360.68)
		)
		(stroke
			(width 0)
			(type default)
		)
	)
	(wire
		(pts
			(xy 50.8 93.98) (xy 71.12 93.98)
		)
		(stroke
			(width 0)
			(type default)
		)
	)
	(wire
		(pts
			(xy 184.15 306.07) (xy 184.15 308.61)
		)
		(stroke
			(width 0)
			(type default)
		)
	)
	(wire
		(pts
			(xy 139.7 289.56) (xy 139.7 288.29)
		)
		(stroke
			(width 0)
			(type default)
		)
	)
	(wire
		(pts
			(xy 179.07 212.09) (xy 182.88 212.09)
		)
		(stroke
			(width 0)
			(type default)
		)
	)
	(wire
		(pts
			(xy 229.87 83.82) (xy 243.84 83.82)
		)
		(stroke
			(width 0)
			(type default)
		)
	)
	(wire
		(pts
			(xy 101.6 374.65) (xy 106.68 374.65)
		)
		(stroke
			(width 0)
			(type default)
		)
	)
	(wire
		(pts
			(xy 222.25 365.76) (xy 220.98 365.76)
		)
		(stroke
			(width 0)
			(type default)
		)
	)
	(wire
		(pts
			(xy 255.27 81.28) (xy 262.89 81.28)
		)
		(stroke
			(width 0)
			(type default)
		)
	)
	(wire
		(pts
			(xy 127 93.98) (xy 129.54 93.98)
		)
		(stroke
			(width 0)
			(type default)
		)
	)
	(wire
		(pts
			(xy 187.96 227.33) (xy 194.31 227.33)
		)
		(stroke
			(width 0)
			(type default)
		)
	)
	(wire
		(pts
			(xy 229.87 96.52) (xy 233.68 96.52)
		)
		(stroke
			(width 0)
			(type default)
		)
	)
	(wire
		(pts
			(xy 194.31 212.09) (xy 194.31 209.55)
		)
		(stroke
			(width 0)
			(type default)
		)
	)
	(wire
		(pts
			(xy 134.62 93.98) (xy 137.16 93.98)
		)
		(stroke
			(width 0)
			(type default)
		)
	)
	(wire
		(pts
			(xy 40.64 281.94) (xy 44.45 281.94)
		)
		(stroke
			(width 0)
			(type default)
		)
	)
	(wire
		(pts
			(xy 220.98 365.76) (xy 220.98 368.3)
		)
		(stroke
			(width 0)
			(type default)
		)
	)
	(wire
		(pts
			(xy 111.76 190.5) (xy 111.76 189.23)
		)
		(stroke
			(width 0)
			(type default)
		)
	)
	(wire
		(pts
			(xy 41.91 294.64) (xy 44.45 294.64)
		)
		(stroke
			(width 0)
			(type default)
		)
	)
	(wire
		(pts
			(xy 109.22 284.48) (xy 115.57 284.48)
		)
		(stroke
			(width 0)
			(type default)
		)
	)
	(wire
		(pts
			(xy 187.96 207.01) (xy 194.31 207.01)
		)
		(stroke
			(width 0)
			(type default)
		)
	)
	(wire
		(pts
			(xy 215.9 353.06) (xy 215.9 355.6)
		)
		(stroke
			(width 0)
			(type default)
		)
	)
	(wire
		(pts
			(xy 179.07 227.33) (xy 182.88 227.33)
		)
		(stroke
			(width 0)
			(type default)
		)
	)
	(wire
		(pts
			(xy 208.28 220.98) (xy 208.28 223.52)
		)
		(stroke
			(width 0)
			(type default)
		)
	)
	(text "Thunderbolt Controller"
		(exclude_from_sim no)
		(at 128.27 22.606 0)
		(effects
			(font
				(size 2.54 2.54)
				(thickness 0.508)
				(bold yes)
			)
			(justify left bottom)
		)
	)
	(text "PCIe Clock Generator"
		(exclude_from_sim no)
		(at 204.47 340.995 0)
		(effects
			(font
				(size 2.54 2.54)
				(thickness 0.508)
				(bold yes)
			)
			(justify left bottom)
		)
	)
	(text "SPI Flash Memory"
		(exclude_from_sim no)
		(at 55.88 343.535 0)
		(effects
			(font
				(size 2.54 2.54)
				(thickness 0.508)
				(bold yes)
			)
			(justify left bottom)
		)
	)
	(text "Support 150-mils and 200-mils package"
		(exclude_from_sim no)
		(at 54.61 392.43 0)
		(effects
			(font
				(size 1.27 1.27)
			)
			(justify left bottom)
		)
	)
	(label "FLASH_HOLD"
		(at 31.75 379.73 0)
		(fields_autoplaced yes)
		(effects
			(font
				(size 1.27 1.27)
			)
			(justify left bottom)
		)
	)
	(label "PCIE_CLK_JHL_P"
		(at 262.89 363.22 180)
		(fields_autoplaced yes)
		(effects
			(font
				(size 1.27 1.27)
			)
			(justify right bottom)
		)
	)
	(label "TX2_P"
		(at 231.14 73.66 0)
		(fields_autoplaced yes)
		(effects
			(font
				(size 1.27 1.27)
			)
			(justify left bottom)
		)
	)
	(label "PA_TX0_N"
		(at 59.69 66.04 0)
		(fields_autoplaced yes)
		(effects
			(font
				(size 1.27 1.27)
			)
			(justify left bottom)
		)
	)
	(label "TX2_N"
		(at 231.14 76.2 0)
		(fields_autoplaced yes)
		(effects
			(font
				(size 1.27 1.27)
			)
			(justify left bottom)
		)
	)
	(label "PA_TX1_N"
		(at 59.69 73.66 0)
		(fields_autoplaced yes)
		(effects
			(font
				(size 1.27 1.27)
			)
			(justify left bottom)
		)
	)
	(label "FLASH_WP"
		(at 187.96 199.39 180)
		(fields_autoplaced yes)
		(effects
			(font
				(size 1.27 1.27)
			)
			(justify right bottom)
		)
	)
	(label "PCIE_CLK_JHL_P"
		(at 157.48 88.9 0)
		(fields_autoplaced yes)
		(effects
			(font
				(size 1.27 1.27)
			)
			(justify left bottom)
		)
	)
	(label "PA_AUX_P"
		(at 59.69 78.74 0)
		(fields_autoplaced yes)
		(effects
			(font
				(size 1.27 1.27)
			)
			(justify left bottom)
		)
	)
	(label "TX3_P"
		(at 231.14 81.28 0)
		(fields_autoplaced yes)
		(effects
			(font
				(size 1.27 1.27)
			)
			(justify left bottom)
		)
	)
	(label "TX1_N"
		(at 231.14 68.58 0)
		(fields_autoplaced yes)
		(effects
			(font
				(size 1.27 1.27)
			)
			(justify left bottom)
		)
	)
	(label "FLASH_WP"
		(at 102.87 377.19 0)
		(fields_autoplaced yes)
		(effects
			(font
				(size 1.27 1.27)
			)
			(justify left bottom)
		)
	)
	(label "PA_AUX_N"
		(at 59.69 81.28 0)
		(fields_autoplaced yes)
		(effects
			(font
				(size 1.27 1.27)
			)
			(justify left bottom)
		)
	)
	(label "TX0_P"
		(at 231.14 58.42 0)
		(fields_autoplaced yes)
		(effects
			(font
				(size 1.27 1.27)
			)
			(justify left bottom)
		)
	)
	(label "TX0_N"
		(at 231.14 60.96 0)
		(fields_autoplaced yes)
		(effects
			(font
				(size 1.27 1.27)
			)
			(justify left bottom)
		)
	)
	(label "PCIE_CLK_JHL_N"
		(at 262.89 365.76 180)
		(fields_autoplaced yes)
		(effects
			(font
				(size 1.27 1.27)
			)
			(justify right bottom)
		)
	)
	(label "FLASH_HOLD"
		(at 102.87 379.73 0)
		(fields_autoplaced yes)
		(effects
			(font
				(size 1.27 1.27)
			)
			(justify left bottom)
		)
	)
	(label "PA_TX0_P"
		(at 59.69 63.5 0)
		(fields_autoplaced yes)
		(effects
			(font
				(size 1.27 1.27)
			)
			(justify left bottom)
		)
	)
	(label "FLASH_WP"
		(at 31.75 377.19 0)
		(fields_autoplaced yes)
		(effects
			(font
				(size 1.27 1.27)
			)
			(justify left bottom)
		)
	)
	(label "TX1_P"
		(at 231.14 66.04 0)
		(fields_autoplaced yes)
		(effects
			(font
				(size 1.27 1.27)
			)
			(justify left bottom)
		)
	)
	(label "PCIE_CLK_JHL_N"
		(at 157.48 91.44 0)
		(fields_autoplaced yes)
		(effects
			(font
				(size 1.27 1.27)
			)
			(justify left bottom)
		)
	)
	(label "TX3_N"
		(at 231.14 83.82 0)
		(fields_autoplaced yes)
		(effects
			(font
				(size 1.27 1.27)
			)
			(justify left bottom)
		)
	)
	(label "PA_TX1_P"
		(at 59.69 71.12 0)
		(fields_autoplaced yes)
		(effects
			(font
				(size 1.27 1.27)
			)
			(justify left bottom)
		)
	)
	(global_label "PCIE_TX3_P"
		(shape input)
		(at 262.89 81.28 0)
		(fields_autoplaced yes)
		(effects
			(font
				(size 1.27 1.27)
			)
			(justify left)
		)
		(property "Intersheetrefs" "${INTERSHEET_REFS}"
			(at 276.1888 81.2006 0)
			(effects
				(font
					(size 1.27 1.27)
				)
				(justify left)
				(hide yes)
			)
		)
	)
	(global_label "3V3_SYS"
		(shape input)
		(at 31.75 281.94 180)
		(fields_autoplaced yes)
		(effects
			(font
				(size 1.27 1.27)
			)
			(justify right)
		)
		(property "Intersheetrefs" "${INTERSHEET_REFS}"
			(at 21.354 281.8606 0)
			(effects
				(font
					(size 1.27 1.27)
				)
				(justify right)
				(hide yes)
			)
		)
	)
	(global_label "PCIE_TX2_N"
		(shape input)
		(at 262.89 76.2 0)
		(fields_autoplaced yes)
		(effects
			(font
				(size 1.27 1.27)
			)
			(justify left)
		)
		(property "Intersheetrefs" "${INTERSHEET_REFS}"
			(at 276.2493 76.1206 0)
			(effects
				(font
					(size 1.27 1.27)
				)
				(justify left)
				(hide yes)
			)
		)
	)
	(global_label "HPD"
		(shape input)
		(at 67.31 99.06 180)
		(fields_autoplaced yes)
		(effects
			(font
				(size 1.27 1.27)
			)
			(justify right)
		)
		(property "Intersheetrefs" "${INTERSHEET_REFS}"
			(at 61.0264 98.9806 0)
			(effects
				(font
					(size 1.27 1.27)
				)
				(justify right)
				(hide yes)
			)
		)
	)
	(global_label "SPI_SCLK"
		(shape input)
		(at 31.75 382.27 180)
		(fields_autoplaced yes)
		(effects
			(font
				(size 1.27 1.27)
			)
			(justify right)
		)
		(property "Intersheetrefs" "${INTERSHEET_REFS}"
			(at 20.5074 382.3494 0)
			(effects
				(font
					(size 1.27 1.27)
				)
				(justify right)
				(hide yes)
			)
		)
	)
	(global_label "SPI_SCLK"
		(shape input)
		(at 133.35 382.27 0)
		(fields_autoplaced yes)
		(effects
			(font
				(size 1.27 1.27)
			)
			(justify left)
		)
		(property "Intersheetrefs" "${INTERSHEET_REFS}"
			(at 144.5926 382.1906 0)
			(effects
				(font
					(size 1.27 1.27)
				)
				(justify left)
				(hide yes)
			)
		)
	)
	(global_label "3V3_SYS"
		(shape input)
		(at 38.1 353.06 180)
		(fields_autoplaced yes)
		(effects
			(font
				(size 1.27 1.27)
			)
			(justify right)
		)
		(property "Intersheetrefs" "${INTERSHEET_REFS}"
			(at 27.704 353.1394 0)
			(effects
				(font
					(size 1.27 1.27)
				)
				(justify right)
				(hide yes)
			)
		)
	)
	(global_label "SPI_MISO"
		(shape input)
		(at 31.75 374.65 180)
		(fields_autoplaced yes)
		(effects
			(font
				(size 1.27 1.27)
			)
			(justify right)
		)
		(property "Intersheetrefs" "${INTERSHEET_REFS}"
			(at 20.6888 374.7294 0)
			(effects
				(font
					(size 1.27 1.27)
				)
				(justify right)
				(hide yes)
			)
		)
	)
	(global_label "AUX_N"
		(shape input)
		(at 27.94 81.28 180)
		(fields_autoplaced yes)
		(effects
			(font
				(size 1.27 1.27)
			)
			(justify right)
		)
		(property "Intersheetrefs" "${INTERSHEET_REFS}"
			(at 19.6002 81.2006 0)
			(effects
				(font
					(size 1.27 1.27)
				)
				(justify right)
				(hide yes)
			)
		)
	)
	(global_label "3V3_SYS"
		(shape input)
		(at 212.09 346.71 180)
		(fields_autoplaced yes)
		(effects
			(font
				(size 1.27 1.27)
			)
			(justify right)
		)
		(property "Intersheetrefs" "${INTERSHEET_REFS}"
			(at 201.694 346.6306 0)
			(effects
				(font
					(size 1.27 1.27)
				)
				(justify right)
				(hide yes)
			)
		)
	)
	(global_label "I2C1_IRQ"
		(shape input)
		(at 193.04 222.25 0)
		(fields_autoplaced yes)
		(effects
			(font
				(size 1.27 1.27)
			)
			(justify left)
		)
		(property "Intersheetrefs" "${INTERSHEET_REFS}"
			(at 203.9198 222.1706 0)
			(effects
				(font
					(size 1.27 1.27)
				)
				(justify left)
				(hide yes)
			)
		)
	)
	(global_label "SPI_CS"
		(shape input)
		(at 109.22 304.8 0)
		(fields_autoplaced yes)
		(effects
			(font
				(size 1.27 1.27)
			)
			(justify left)
		)
		(property "Intersheetrefs" "${INTERSHEET_REFS}"
			(at 118.1645 304.7206 0)
			(effects
				(font
					(size 1.27 1.27)
				)
				(justify left)
				(hide yes)
			)
		)
	)
	(global_label "TB_RX0_P"
		(shape input)
		(at 59.69 48.26 180)
		(fields_autoplaced yes)
		(effects
			(font
				(size 1.27 1.27)
			)
			(justify right)
		)
		(property "Intersheetrefs" "${INTERSHEET_REFS}"
			(at 48.145 48.1806 0)
			(effects
				(font
					(size 1.27 1.27)
				)
				(justify right)
				(hide yes)
			)
		)
	)
	(global_label "PCIE_TX0_N"
		(shape input)
		(at 262.89 60.96 0)
		(fields_autoplaced yes)
		(effects
			(font
				(size 1.27 1.27)
			)
			(justify left)
		)
		(property "Intersheetrefs" "${INTERSHEET_REFS}"
			(at 276.2493 60.8806 0)
			(effects
				(font
					(size 1.27 1.27)
				)
				(justify left)
				(hide yes)
			)
		)
	)
	(global_label "SPI_MOSI"
		(shape input)
		(at 109.22 299.72 0)
		(fields_autoplaced yes)
		(effects
			(font
				(size 1.27 1.27)
			)
			(justify left)
		)
		(property "Intersheetrefs" "${INTERSHEET_REFS}"
			(at 120.2812 299.6406 0)
			(effects
				(font
					(size 1.27 1.27)
				)
				(justify left)
				(hide yes)
			)
		)
	)
	(global_label "PCIE_RX3_N"
		(shape input)
		(at 157.48 83.82 180)
		(fields_autoplaced yes)
		(effects
			(font
				(size 1.27 1.27)
			)
			(justify right)
		)
		(property "Intersheetrefs" "${INTERSHEET_REFS}"
			(at 143.8183 83.7406 0)
			(effects
				(font
					(size 1.27 1.27)
				)
				(justify right)
				(hide yes)
			)
		)
	)
	(global_label "PCIE_RX2_N"
		(shape input)
		(at 157.48 76.2 180)
		(fields_autoplaced yes)
		(effects
			(font
				(size 1.27 1.27)
			)
			(justify right)
		)
		(property "Intersheetrefs" "${INTERSHEET_REFS}"
			(at 143.8183 76.1206 0)
			(effects
				(font
					(size 1.27 1.27)
				)
				(justify right)
				(hide yes)
			)
		)
	)
	(global_label "PCIE_PWRGD"
		(shape input)
		(at 232.41 91.44 0)
		(fields_autoplaced yes)
		(effects
			(font
				(size 1.27 1.27)
			)
			(justify left)
		)
		(property "Intersheetrefs" "${INTERSHEET_REFS}"
			(at 246.616 91.3606 0)
			(effects
				(font
					(size 1.27 1.27)
				)
				(justify left)
				(hide yes)
			)
		)
	)
	(global_label "PCIE_RX0_N"
		(shape input)
		(at 157.48 60.96 180)
		(fields_autoplaced yes)
		(effects
			(font
				(size 1.27 1.27)
			)
			(justify right)
		)
		(property "Intersheetrefs" "${INTERSHEET_REFS}"
			(at 143.8183 60.8806 0)
			(effects
				(font
					(size 1.27 1.27)
				)
				(justify right)
				(hide yes)
			)
		)
	)
	(global_label "PCIE_RX2_P"
		(shape input)
		(at 157.48 73.66 180)
		(fields_autoplaced yes)
		(effects
			(font
				(size 1.27 1.27)
			)
			(justify right)
		)
		(property "Intersheetrefs" "${INTERSHEET_REFS}"
			(at 143.8788 73.5806 0)
			(effects
				(font
					(size 1.27 1.27)
				)
				(justify right)
				(hide yes)
			)
		)
	)
	(global_label "PCIE_RX0_P"
		(shape input)
		(at 157.48 58.42 180)
		(fields_autoplaced yes)
		(effects
			(font
				(size 1.27 1.27)
			)
			(justify right)
		)
		(property "Intersheetrefs" "${INTERSHEET_REFS}"
			(at 143.8788 58.3406 0)
			(effects
				(font
					(size 1.27 1.27)
				)
				(justify right)
				(hide yes)
			)
		)
	)
	(global_label "3V3_SYS"
		(shape input)
		(at 193.04 224.79 0)
		(fields_autoplaced yes)
		(effects
			(font
				(size 1.27 1.27)
			)
			(justify left)
		)
		(property "Intersheetrefs" "${INTERSHEET_REFS}"
			(at 203.436 224.7106 0)
			(effects
				(font
					(size 1.27 1.27)
				)
				(justify left)
				(hide yes)
			)
		)
	)
	(global_label "USB_RP_P"
		(shape input)
		(at 57.15 86.36 180)
		(fields_autoplaced yes)
		(effects
			(font
				(size 1.27 1.27)
			)
			(justify right)
		)
		(property "Intersheetrefs" "${INTERSHEET_REFS}"
			(at 45.1817 86.2806 0)
			(effects
				(font
					(size 1.27 1.27)
				)
				(justify right)
				(hide yes)
			)
		)
	)
	(global_label "LSX_R2P"
		(shape input)
		(at 35.56 93.98 180)
		(fields_autoplaced yes)
		(effects
			(font
				(size 1.27 1.27)
			)
			(justify right)
		)
		(property "Intersheetrefs" "${INTERSHEET_REFS}"
			(at 24.9826 93.9006 0)
			(effects
				(font
					(size 1.27 1.27)
				)
				(justify right)
				(hide yes)
			)
		)
	)
	(global_label "3V3_SYS"
		(shape input)
		(at 208.28 220.98 90)
		(fields_autoplaced yes)
		(effects
			(font
				(size 1.27 1.27)
			)
			(justify left)
		)
		(property "Intersheetrefs" "${INTERSHEET_REFS}"
			(at 208.2006 210.584 90)
			(effects
				(font
					(size 1.27 1.27)
				)
				(justify left)
				(hide yes)
			)
		)
	)
	(global_label "3V3_SYS"
		(shape input)
		(at 133.35 379.73 0)
		(fields_autoplaced yes)
		(effects
			(font
				(size 1.27 1.27)
			)
			(justify left)
		)
		(property "Intersheetrefs" "${INTERSHEET_REFS}"
			(at 143.746 379.6506 0)
			(effects
				(font
					(size 1.27 1.27)
				)
				(justify left)
				(hide yes)
			)
		)
	)
	(global_label "TB_RX0_N"
		(shape input)
		(at 59.69 50.8 180)
		(fields_autoplaced yes)
		(effects
			(font
				(size 1.27 1.27)
			)
			(justify right)
		)
		(property "Intersheetrefs" "${INTERSHEET_REFS}"
			(at 48.0845 50.7206 0)
			(effects
				(font
					(size 1.27 1.27)
				)
				(justify right)
				(hide yes)
			)
		)
	)
	(global_label "TB_TX0_N"
		(shape input)
		(at 27.94 66.04 180)
		(fields_autoplaced yes)
		(effects
			(font
				(size 1.27 1.27)
			)
			(justify right)
		)
		(property "Intersheetrefs" "${INTERSHEET_REFS}"
			(at 16.6369 65.9606 0)
			(effects
				(font
					(size 1.27 1.27)
				)
				(justify right)
				(hide yes)
			)
		)
	)
	(global_label "I2C1_SCL"
		(shape input)
		(at 187.96 196.85 0)
		(fields_autoplaced yes)
		(effects
			(font
				(size 1.27 1.27)
			)
			(justify left)
		)
		(property "Intersheetrefs" "${INTERSHEET_REFS}"
			(at 199.1421 196.7706 0)
			(effects
				(font
					(size 1.27 1.27)
				)
				(justify left)
				(hide yes)
			)
		)
	)
	(global_label "3V3_SYS"
		(shape input)
		(at 162.56 96.52 180)
		(fields_autoplaced yes)
		(effects
			(font
				(size 1.27 1.27)
			)
			(justify right)
		)
		(property "Intersheetrefs" "${INTERSHEET_REFS}"
			(at 152.164 96.4406 0)
			(effects
				(font
					(size 1.27 1.27)
				)
				(justify right)
				(hide yes)
			)
		)
	)
	(global_label "TB_RX1_P"
		(shape input)
		(at 59.69 55.88 180)
		(fields_autoplaced yes)
		(effects
			(font
				(size 1.27 1.27)
			)
			(justify right)
		)
		(property "Intersheetrefs" "${INTERSHEET_REFS}"
			(at 48.145 55.9594 0)
			(effects
				(font
					(size 1.27 1.27)
				)
				(justify right)
				(hide yes)
			)
		)
	)
	(global_label "TB_TX1_N"
		(shape input)
		(at 27.94 73.66 180)
		(fields_autoplaced yes)
		(effects
			(font
				(size 1.27 1.27)
			)
			(justify right)
		)
		(property "Intersheetrefs" "${INTERSHEET_REFS}"
			(at 16.6369 73.7394 0)
			(effects
				(font
					(size 1.27 1.27)
				)
				(justify right)
				(hide yes)
			)
		)
	)
	(global_label "SPI_MISO"
		(shape input)
		(at 109.22 302.26 0)
		(fields_autoplaced yes)
		(effects
			(font
				(size 1.27 1.27)
			)
			(justify left)
		)
		(property "Intersheetrefs" "${INTERSHEET_REFS}"
			(at 120.2812 302.1806 0)
			(effects
				(font
					(size 1.27 1.27)
				)
				(justify left)
				(hide yes)
			)
		)
	)
	(global_label "PCIE_TX2_P"
		(shape input)
		(at 262.89 73.66 0)
		(fields_autoplaced yes)
		(effects
			(font
				(size 1.27 1.27)
			)
			(justify left)
		)
		(property "Intersheetrefs" "${INTERSHEET_REFS}"
			(at 276.1888 73.5806 0)
			(effects
				(font
					(size 1.27 1.27)
				)
				(justify left)
				(hide yes)
			)
		)
	)
	(global_label "SPI_CS"
		(shape input)
		(at 31.75 384.81 180)
		(fields_autoplaced yes)
		(effects
			(font
				(size 1.27 1.27)
			)
			(justify right)
		)
		(property "Intersheetrefs" "${INTERSHEET_REFS}"
			(at 22.8055 384.8894 0)
			(effects
				(font
					(size 1.27 1.27)
				)
				(justify right)
				(hide yes)
			)
		)
	)
	(global_label "AUX_P"
		(shape input)
		(at 27.94 78.74 180)
		(fields_autoplaced yes)
		(effects
			(font
				(size 1.27 1.27)
			)
			(justify right)
		)
		(property "Intersheetrefs" "${INTERSHEET_REFS}"
			(at 19.6607 78.6606 0)
			(effects
				(font
					(size 1.27 1.27)
				)
				(justify right)
				(hide yes)
			)
		)
	)
	(global_label "USB_RP_N"
		(shape input)
		(at 57.15 88.9 180)
		(fields_autoplaced yes)
		(effects
			(font
				(size 1.27 1.27)
			)
			(justify right)
		)
		(property "Intersheetrefs" "${INTERSHEET_REFS}"
			(at 45.1212 88.8206 0)
			(effects
				(font
					(size 1.27 1.27)
				)
				(justify right)
				(hide yes)
			)
		)
	)
	(global_label "PCIE_RX1_P"
		(shape input)
		(at 157.48 66.04 180)
		(fields_autoplaced yes)
		(effects
			(font
				(size 1.27 1.27)
			)
			(justify right)
		)
		(property "Intersheetrefs" "${INTERSHEET_REFS}"
			(at 143.8788 65.9606 0)
			(effects
				(font
					(size 1.27 1.27)
				)
				(justify right)
				(hide yes)
			)
		)
	)
	(global_label "PCIE_RX3_P"
		(shape input)
		(at 157.48 81.28 180)
		(fields_autoplaced yes)
		(effects
			(font
				(size 1.27 1.27)
			)
			(justify right)
		)
		(property "Intersheetrefs" "${INTERSHEET_REFS}"
			(at 143.8788 81.2006 0)
			(effects
				(font
					(size 1.27 1.27)
				)
				(justify right)
				(hide yes)
			)
		)
	)
	(global_label "LSX_P2R"
		(shape input)
		(at 35.56 96.52 180)
		(fields_autoplaced yes)
		(effects
			(font
				(size 1.27 1.27)
			)
			(justify right)
		)
		(property "Intersheetrefs" "${INTERSHEET_REFS}"
			(at 24.9826 96.4406 0)
			(effects
				(font
					(size 1.27 1.27)
				)
				(justify right)
				(hide yes)
			)
		)
	)
	(global_label "PCIE_TX3_N"
		(shape input)
		(at 262.89 83.82 0)
		(fields_autoplaced yes)
		(effects
			(font
				(size 1.27 1.27)
			)
			(justify left)
		)
		(property "Intersheetrefs" "${INTERSHEET_REFS}"
			(at 276.2493 83.7406 0)
			(effects
				(font
					(size 1.27 1.27)
				)
				(justify left)
				(hide yes)
			)
		)
	)
	(global_label "PCIE_TX1_N"
		(shape input)
		(at 262.89 68.58 0)
		(fields_autoplaced yes)
		(effects
			(font
				(size 1.27 1.27)
			)
			(justify left)
		)
		(property "Intersheetrefs" "${INTERSHEET_REFS}"
			(at 276.2493 68.5006 0)
			(effects
				(font
					(size 1.27 1.27)
				)
				(justify left)
				(hide yes)
			)
		)
	)
	(global_label "SPI_MOSI"
		(shape input)
		(at 31.75 372.11 180)
		(fields_autoplaced yes)
		(effects
			(font
				(size 1.27 1.27)
			)
			(justify right)
		)
		(property "Intersheetrefs" "${INTERSHEET_REFS}"
			(at 20.6888 372.1894 0)
			(effects
				(font
					(size 1.27 1.27)
				)
				(justify right)
				(hide yes)
			)
		)
	)
	(global_label "3V3_SYS"
		(shape input)
		(at 106.68 356.87 90)
		(fields_autoplaced yes)
		(effects
			(font
				(size 1.27 1.27)
			)
			(justify left)
		)
		(property "Intersheetrefs" "${INTERSHEET_REFS}"
			(at 106.6006 346.474 90)
			(effects
				(font
					(size 1.27 1.27)
				)
				(justify left)
				(hide yes)
			)
		)
	)
	(global_label "PCIE_RX1_N"
		(shape input)
		(at 157.48 68.58 180)
		(fields_autoplaced yes)
		(effects
			(font
				(size 1.27 1.27)
			)
			(justify right)
		)
		(property "Intersheetrefs" "${INTERSHEET_REFS}"
			(at 143.8183 68.5006 0)
			(effects
				(font
					(size 1.27 1.27)
				)
				(justify right)
				(hide yes)
			)
		)
	)
	(global_label "PCIE_CLK_CON_N"
		(shape input)
		(at 262.89 360.68 0)
		(fields_autoplaced yes)
		(effects
			(font
				(size 1.27 1.27)
			)
			(justify left)
		)
		(property "Intersheetrefs" "${INTERSHEET_REFS}"
			(at 281.3293 360.6006 0)
			(effects
				(font
					(size 1.27 1.27)
				)
				(justify left)
				(hide yes)
			)
		)
	)
	(global_label "PCIE_TX1_P"
		(shape input)
		(at 262.89 66.04 0)
		(fields_autoplaced yes)
		(effects
			(font
				(size 1.27 1.27)
			)
			(justify left)
		)
		(property "Intersheetrefs" "${INTERSHEET_REFS}"
			(at 276.1888 65.9606 0)
			(effects
				(font
					(size 1.27 1.27)
				)
				(justify left)
				(hide yes)
			)
		)
	)
	(global_label "SPI_SCLK"
		(shape input)
		(at 109.22 307.34 0)
		(fields_autoplaced yes)
		(effects
			(font
				(size 1.27 1.27)
			)
			(justify left)
		)
		(property "Intersheetrefs" "${INTERSHEET_REFS}"
			(at 120.4626 307.2606 0)
			(effects
				(font
					(size 1.27 1.27)
				)
				(justify left)
				(hide yes)
			)
		)
	)
	(global_label "TB_TX0_P"
		(shape input)
		(at 27.94 63.5 180)
		(fields_autoplaced yes)
		(effects
			(font
				(size 1.27 1.27)
			)
			(justify right)
		)
		(property "Intersheetrefs" "${INTERSHEET_REFS}"
			(at 16.6974 63.4206 0)
			(effects
				(font
					(size 1.27 1.27)
				)
				(justify right)
				(hide yes)
			)
		)
	)
	(global_label "PCIE_CLK_CON_P"
		(shape input)
		(at 262.89 358.14 0)
		(fields_autoplaced yes)
		(effects
			(font
				(size 1.27 1.27)
			)
			(justify left)
		)
		(property "Intersheetrefs" "${INTERSHEET_REFS}"
			(at 281.2688 358.0606 0)
			(effects
				(font
					(size 1.27 1.27)
				)
				(justify left)
				(hide yes)
			)
		)
	)
	(global_label "PCIE_WAKE"
		(shape input)
		(at 210.82 232.41 0)
		(fields_autoplaced yes)
		(effects
			(font
				(size 1.27 1.27)
			)
			(justify left)
		)
		(property "Intersheetrefs" "${INTERSHEET_REFS}"
			(at 223.4536 232.4894 0)
			(effects
				(font
					(size 1.27 1.27)
				)
				(justify left)
				(hide yes)
			)
		)
	)
	(global_label "TB_RX1_N"
		(shape input)
		(at 59.69 58.42 180)
		(fields_autoplaced yes)
		(effects
			(font
				(size 1.27 1.27)
			)
			(justify right)
		)
		(property "Intersheetrefs" "${INTERSHEET_REFS}"
			(at 48.0845 58.4994 0)
			(effects
				(font
					(size 1.27 1.27)
				)
				(justify right)
				(hide yes)
			)
		)
	)
	(global_label "SPI_MOSI"
		(shape input)
		(at 133.35 372.11 0)
		(fields_autoplaced yes)
		(effects
			(font
				(size 1.27 1.27)
			)
			(justify left)
		)
		(property "Intersheetrefs" "${INTERSHEET_REFS}"
			(at 144.4112 372.0306 0)
			(effects
				(font
					(size 1.27 1.27)
				)
				(justify left)
				(hide yes)
			)
		)
	)
	(global_label "TB_TX1_P"
		(shape input)
		(at 27.94 71.12 180)
		(fields_autoplaced yes)
		(effects
			(font
				(size 1.27 1.27)
			)
			(justify right)
		)
		(property "Intersheetrefs" "${INTERSHEET_REFS}"
			(at 16.6974 71.1994 0)
			(effects
				(font
					(size 1.27 1.27)
				)
				(justify right)
				(hide yes)
			)
		)
	)
	(global_label "I2C1_SDA"
		(shape input)
		(at 187.96 194.31 0)
		(fields_autoplaced yes)
		(effects
			(font
				(size 1.27 1.27)
			)
			(justify left)
		)
		(property "Intersheetrefs" "${INTERSHEET_REFS}"
			(at 199.2026 194.2306 0)
			(effects
				(font
					(size 1.27 1.27)
				)
				(justify left)
				(hide yes)
			)
		)
	)
	(global_label "PCIE_TX0_P"
		(shape input)
		(at 262.89 58.42 0)
		(fields_autoplaced yes)
		(effects
			(font
				(size 1.27 1.27)
			)
			(justify left)
		)
		(property "Intersheetrefs" "${INTERSHEET_REFS}"
			(at 276.1888 58.3406 0)
			(effects
				(font
					(size 1.27 1.27)
				)
				(justify left)
				(hide yes)
			)
		)
	)
	(global_label "SPI_CS"
		(shape input)
		(at 133.35 384.81 0)
		(fields_autoplaced yes)
		(effects
			(font
				(size 1.27 1.27)
			)
			(justify left)
		)
		(property "Intersheetrefs" "${INTERSHEET_REFS}"
			(at 142.2945 384.7306 0)
			(effects
				(font
					(size 1.27 1.27)
				)
				(justify left)
				(hide yes)
			)
		)
	)
	(global_label "SPI_MISO"
		(shape input)
		(at 133.35 374.65 0)
		(fields_autoplaced yes)
		(effects
			(font
				(size 1.27 1.27)
			)
			(justify left)
		)
		(property "Intersheetrefs" "${INTERSHEET_REFS}"
			(at 144.4112 374.5706 0)
			(effects
				(font
					(size 1.27 1.27)
				)
				(justify left)
				(hide yes)
			)
		)
	)
	(global_label "RESET_N"
		(shape input)
		(at 101.6 287.02 0)
		(fields_autoplaced yes)
		(effects
			(font
				(size 1.27 1.27)
			)
			(justify left)
		)
		(property "Intersheetrefs" "${INTERSHEET_REFS}"
			(at 112.0564 286.9406 0)
			(effects
				(font
					(size 1.27 1.27)
				)
				(justify left)
				(hide yes)
			)
		)
	)
	(global_label "3V3_SYS"
		(shape input)
		(at 73.66 370.84 90)
		(fields_autoplaced yes)
		(effects
			(font
				(size 1.27 1.27)
			)
			(justify left)
		)
		(property "Intersheetrefs" "${INTERSHEET_REFS}"
			(at 73.5806 360.444 90)
			(effects
				(font
					(size 1.27 1.27)
				)
				(justify left)
				(hide yes)
			)
		)
	)
	(symbol
		(lib_id "antmicropower:GND")
		(at 146.05 293.37 90)
		(unit 1)
		(exclude_from_sim no)
		(in_bom yes)
		(on_board yes)
		(dnp no)
		(property "Reference" "#PWR0149"
			(at 152.4 293.37 0)
			(effects
				(font
					(size 1.27 1.27)
				)
				(hide yes)
			)
		)
		(property "Value" "GND"
			(at 149.86 293.37 0)
			(effects
				(font
					(size 1.27 1.27)
				)
			)
		)
		(property "Footprint" ""
			(at 146.05 293.37 0)
			(effects
				(font
					(size 1.27 1.27)
				)
				(hide yes)
			)
		)
		(property "Datasheet" ""
			(at 146.05 293.37 0)
			(effects
				(font
					(size 1.27 1.27)
				)
				(hide yes)
			)
		)
		(property "Description" ""
			(at 146.05 293.37 0)
			(effects
				(font
					(size 1.27 1.27)
				)
				(hide yes)
			)
		)
		(property "Author" "Antmicro"
			(at 153.67 284.48 0)
			(effects
				(font
					(size 1.27 1.27)
					(thickness 0.15)
				)
				(justify left bottom)
				(hide yes)
			)
		)
		(property "License" "Apache-2.0"
			(at 156.21 284.48 0)
			(effects
				(font
					(size 1.27 1.27)
					(thickness 0.15)
				)
				(justify left bottom)
				(hide yes)
			)
		)
		(pin "1"
		)
		(instances
			(project "thunderbolt-gpu-adapter"
				(path ""
					(reference "#PWR0149")
					(unit 1)
				)
			)
		)
	)
	(symbol
		(lib_id "antmicroCapacitors0402:C_10p_0402")
		(at 190.5 356.87 0)
		(unit 1)
		(exclude_from_sim no)
		(in_bom yes)
		(on_board yes)
		(dnp no)
		(fields_autoplaced yes)
		(property "Reference" "C113"
			(at 193.0463 349.885 0)
			(effects
				(font
					(size 1.27 1.27)
					(thickness 0.15)
				)
			)
		)
		(property "Value" "C_10p_0402"
			(at 210.82 367.03 0)
			(effects
				(font
					(size 1.27 1.27)
					(thickness 0.15)
				)
				(justify left bottom)
				(hide yes)
			)
		)
		(property "Footprint" "antmicro-footprints:C_0402_1005Metric"
			(at 210.82 369.57 0)
			(effects
				(font
					(size 1.27 1.27)
					(thickness 0.15)
				)
				(justify left bottom)
				(hide yes)
			)
		)
		(property "Datasheet" "https://www.murata.com/products/productdetail?partno=GCM1555C1H100GA16%23"
			(at 210.82 372.11 0)
			(effects
				(font
					(size 1.27 1.27)
					(thickness 0.15)
				)
				(justify left bottom)
				(hide yes)
			)
		)
		(property "Description" ""
			(at 190.5 356.87 0)
			(effects
				(font
					(size 1.27 1.27)
				)
				(hide yes)
			)
		)
		(property "MPN" "GCM1555C1H100GA16D"
			(at 210.82 374.65 0)
			(effects
				(font
					(size 1.27 1.27)
					(thickness 0.15)
				)
				(justify left bottom)
				(hide yes)
			)
		)
		(property "Manufacturer" "Murata"
			(at 210.82 377.19 0)
			(effects
				(font
					(size 1.27 1.27)
					(thickness 0.15)
				)
				(justify left bottom)
				(hide yes)
			)
		)
		(property "License" "Apache-2.0"
			(at 210.82 379.73 0)
			(effects
				(font
					(size 1.27 1.27)
					(thickness 0.15)
				)
				(justify left bottom)
				(hide yes)
			)
		)
		(property "Val" "10p"
			(at 193.0463 352.425 0)
			(effects
				(font
					(size 1.27 1.27)
					(thickness 0.15)
				)
			)
		)
		(property "Voltage" "50V"
			(at 210.82 384.81 0)
			(effects
				(font
					(size 1.27 1.27)
				)
				(justify left bottom)
				(hide yes)
			)
		)
		(property "Dielectric" "C0G"
			(at 210.82 387.35 0)
			(effects
				(font
					(size 1.27 1.27)
				)
				(justify left bottom)
				(hide yes)
			)
		)
		(property "Author" "Antmicro"
			(at 210.82 382.27 0)
			(effects
				(font
					(size 1.27 1.27)
					(thickness 0.15)
				)
				(justify left bottom)
				(hide yes)
			)
		)
		(pin "1"
		)
		(pin "2"
		)
		(instances
			(project "thunderbolt-gpu-adapter"
				(path ""
					(reference "C113")
					(unit 1)
				)
			)
		)
	)
	(symbol
		(lib_id "antmicroCapacitors0402:C_100n_0402")
		(at 39.37 78.74 0)
		(unit 1)
		(exclude_from_sim no)
		(in_bom yes)
		(on_board yes)
		(dnp no)
		(property "Reference" "C101"
			(at 38.735 77.47 0)
			(effects
				(font
					(size 1.27 1.27)
					(thickness 0.15)
				)
			)
		)
		(property "Value" "C_100n_0402"
			(at 59.69 88.9 0)
			(effects
				(font
					(size 1.27 1.27)
					(thickness 0.15)
				)
				(justify left bottom)
				(hide yes)
			)
		)
		(property "Footprint" "antmicro-footprints:C_0402_1005Metric"
			(at 59.69 91.44 0)
			(effects
				(font
					(size 1.27 1.27)
					(thickness 0.15)
				)
				(justify left bottom)
				(hide yes)
			)
		)
		(property "Datasheet" "https://www.murata.com/products/productdetail?partno=GRM155R61H104KE14%23"
			(at 59.69 93.98 0)
			(effects
				(font
					(size 1.27 1.27)
					(thickness 0.15)
				)
				(justify left bottom)
				(hide yes)
			)
		)
		(property "Description" ""
			(at 39.37 78.74 0)
			(effects
				(font
					(size 1.27 1.27)
				)
				(hide yes)
			)
		)
		(property "MPN" "GRM155R61H104KE14D"
			(at 59.69 96.52 0)
			(effects
				(font
					(size 1.27 1.27)
					(thickness 0.15)
				)
				(justify left bottom)
				(hide yes)
			)
		)
		(property "Manufacturer" "Murata"
			(at 59.69 99.06 0)
			(effects
				(font
					(size 1.27 1.27)
					(thickness 0.15)
				)
				(justify left bottom)
				(hide yes)
			)
		)
		(property "License" "Apache-2.0"
			(at 59.69 101.6 0)
			(effects
				(font
					(size 1.27 1.27)
					(thickness 0.15)
				)
				(justify left bottom)
				(hide yes)
			)
		)
		(property "Val" "100n"
			(at 38.735 80.01 0)
			(effects
				(font
					(size 1.27 1.27)
					(thickness 0.15)
				)
			)
		)
		(property "Voltage" "50V"
			(at 59.69 106.68 0)
			(effects
				(font
					(size 1.27 1.27)
				)
				(justify left bottom)
				(hide yes)
			)
		)
		(property "Dielectric" "X5R"
			(at 59.69 109.22 0)
			(effects
				(font
					(size 1.27 1.27)
				)
				(justify left bottom)
				(hide yes)
			)
		)
		(property "Author" "Antmicro"
			(at 59.69 104.14 0)
			(effects
				(font
					(size 1.27 1.27)
					(thickness 0.15)
				)
				(justify left bottom)
				(hide yes)
			)
		)
		(pin "1"
		)
		(pin "2"
		)
		(instances
			(project "thunderbolt-gpu-adapter"
				(path ""
					(reference "C101")
					(unit 1)
				)
			)
		)
	)
	(symbol
		(lib_id "antmicroResistors0402:R_1M_0402")
		(at 46.99 105.41 90)
		(unit 1)
		(exclude_from_sim no)
		(in_bom yes)
		(on_board yes)
		(dnp no)
		(fields_autoplaced yes)
		(property "Reference" "R54"
			(at 45.085 101.6 90)
			(effects
				(font
					(size 1.27 1.27)
					(thickness 0.15)
				)
				(justify left)
			)
		)
		(property "Value" "R_1M_0402"
			(at 59.69 85.09 0)
			(effects
				(font
					(size 1.27 1.27)
					(thickness 0.15)
				)
				(justify left bottom)
				(hide yes)
			)
		)
		(property "Footprint" "antmicro-footprints:R_0402_1005Metric"
			(at 62.23 85.09 0)
			(effects
				(font
					(size 1.27 1.27)
					(thickness 0.15)
				)
				(justify left bottom)
				(hide yes)
			)
		)
		(property "Datasheet" "https://www.bourns.com/docs/product-datasheets/cr.pdf"
			(at 64.77 85.09 0)
			(effects
				(font
					(size 1.27 1.27)
					(thickness 0.15)
				)
				(justify left bottom)
				(hide yes)
			)
		)
		(property "Description" ""
			(at 46.99 105.41 0)
			(effects
				(font
					(size 1.27 1.27)
				)
				(hide yes)
			)
		)
		(property "MPN" "CR0402-FX-1004GLF"
			(at 67.31 85.09 0)
			(effects
				(font
					(size 1.27 1.27)
					(thickness 0.15)
				)
				(justify left bottom)
				(hide yes)
			)
		)
		(property "Manufacturer" "Bourns"
			(at 69.85 85.09 0)
			(effects
				(font
					(size 1.27 1.27)
					(thickness 0.15)
				)
				(justify left bottom)
				(hide yes)
			)
		)
		(property "License" "Apache-2.0"
			(at 72.39 85.09 0)
			(effects
				(font
					(size 1.27 1.27)
					(thickness 0.15)
				)
				(justify left bottom)
				(hide yes)
			)
		)
		(property "Val" "1M"
			(at 45.085 104.14 90)
			(effects
				(font
					(size 1.27 1.27)
					(thickness 0.15)
				)
				(justify left)
			)
		)
		(property "Tolerance" "1%"
			(at 57.15 85.09 0)
			(effects
				(font
					(size 1.27 1.27)
				)
				(justify left bottom)
				(hide yes)
			)
		)
		(property "Author" "Antmicro"
			(at 74.93 85.09 0)
			(effects
				(font
					(size 1.27 1.27)
					(thickness 0.15)
				)
				(justify left bottom)
				(hide yes)
			)
		)
		(pin "1"
		)
		(pin "2"
		)
		(instances
			(project "thunderbolt-gpu-adapter"
				(path ""
					(reference "R54")
					(unit 1)
				)
			)
		)
	)
	(symbol
		(lib_id "antmicropower:GND")
		(at 149.86 299.72 90)
		(unit 1)
		(exclude_from_sim no)
		(in_bom yes)
		(on_board yes)
		(dnp no)
		(property "Reference" "#PWR0151"
			(at 156.21 299.72 0)
			(effects
				(font
					(size 1.27 1.27)
				)
				(hide yes)
			)
		)
		(property "Value" "GND"
			(at 153.67 299.72 0)
			(effects
				(font
					(size 1.27 1.27)
				)
			)
		)
		(property "Footprint" ""
			(at 149.86 299.72 0)
			(effects
				(font
					(size 1.27 1.27)
				)
				(hide yes)
			)
		)
		(property "Datasheet" ""
			(at 149.86 299.72 0)
			(effects
				(font
					(size 1.27 1.27)
				)
				(hide yes)
			)
		)
		(property "Description" ""
			(at 149.86 299.72 0)
			(effects
				(font
					(size 1.27 1.27)
				)
				(hide yes)
			)
		)
		(property "Author" "Antmicro"
			(at 157.48 290.83 0)
			(effects
				(font
					(size 1.27 1.27)
					(thickness 0.15)
				)
				(justify left bottom)
				(hide yes)
			)
		)
		(property "License" "Apache-2.0"
			(at 160.02 290.83 0)
			(effects
				(font
					(size 1.27 1.27)
					(thickness 0.15)
				)
				(justify left bottom)
				(hide yes)
			)
		)
		(pin "1"
		)
		(instances
			(project "thunderbolt-gpu-adapter"
				(path ""
					(reference "#PWR0151")
					(unit 1)
				)
			)
		)
	)
	(symbol
		(lib_id "antmicroCapacitors0402:C_220n_0402")
		(at 243.84 68.58 0)
		(unit 1)
		(exclude_from_sim no)
		(in_bom yes)
		(on_board yes)
		(dnp no)
		(property "Reference" "C106"
			(at 242.57 67.31 0)
			(effects
				(font
					(size 1.27 1.27)
					(thickness 0.15)
				)
			)
		)
		(property "Value" "C_220n_0402"
			(at 264.16 78.74 0)
			(effects
				(font
					(size 1.27 1.27)
					(thickness 0.15)
				)
				(justify left bottom)
				(hide yes)
			)
		)
		(property "Footprint" "antmicro-footprints:C_0402_1005Metric"
			(at 264.16 81.28 0)
			(effects
				(font
					(size 1.27 1.27)
					(thickness 0.15)
				)
				(justify left bottom)
				(hide yes)
			)
		)
		(property "Datasheet" "https://www.yageo.com/en/Chart/Download/pdf/CC0402KRX5R6BB224"
			(at 264.16 83.82 0)
			(effects
				(font
					(size 1.27 1.27)
					(thickness 0.15)
				)
				(justify left bottom)
				(hide yes)
			)
		)
		(property "Description" ""
			(at 243.84 68.58 0)
			(effects
				(font
					(size 1.27 1.27)
				)
				(hide yes)
			)
		)
		(property "MPN" "CC0402KRX5R6BB224"
			(at 264.16 86.36 0)
			(effects
				(font
					(size 1.27 1.27)
					(thickness 0.15)
				)
				(justify left bottom)
				(hide yes)
			)
		)
		(property "Manufacturer" "YAGEO"
			(at 264.16 88.9 0)
			(effects
				(font
					(size 1.27 1.27)
					(thickness 0.15)
				)
				(justify left bottom)
				(hide yes)
			)
		)
		(property "License" "Apache-2.0"
			(at 264.16 91.44 0)
			(effects
				(font
					(size 1.27 1.27)
					(thickness 0.15)
				)
				(justify left bottom)
				(hide yes)
			)
		)
		(property "Val" "220n"
			(at 242.57 69.85 0)
			(effects
				(font
					(size 1.27 1.27)
					(thickness 0.15)
				)
			)
		)
		(property "Voltage" ""
			(at 264.16 96.52 0)
			(effects
				(font
					(size 1.27 1.27)
				)
				(justify left bottom)
				(hide yes)
			)
		)
		(property "Dielectric" ""
			(at 264.16 99.06 0)
			(effects
				(font
					(size 1.27 1.27)
				)
				(justify left bottom)
				(hide yes)
			)
		)
		(property "Author" "Antmicro"
			(at 264.16 93.98 0)
			(effects
				(font
					(size 1.27 1.27)
					(thickness 0.15)
				)
				(justify left bottom)
				(hide yes)
			)
		)
		(pin "1"
		)
		(pin "2"
		)
		(instances
			(project "thunderbolt-gpu-adapter"
				(path ""
					(reference "C106")
					(unit 1)
				)
			)
		)
	)
	(symbol
		(lib_id "antmicroResistors0402:R_3k01_0402")
		(at 233.68 96.52 0)
		(unit 1)
		(exclude_from_sim no)
		(in_bom yes)
		(on_board yes)
		(dnp no)
		(fields_autoplaced yes)
		(property "Reference" "R74"
			(at 236.22 100.33 0)
			(effects
				(font
					(size 1.27 1.27)
					(thickness 0.15)
				)
			)
		)
		(property "Value" "R_3k01_0402"
			(at 254 109.22 0)
			(effects
				(font
					(size 1.27 1.27)
					(thickness 0.15)
				)
				(justify left bottom)
				(hide yes)
			)
		)
		(property "Footprint" "antmicro-footprints:R_0402_1005Metric"
			(at 254 111.76 0)
			(effects
				(font
					(size 1.27 1.27)
					(thickness 0.15)
				)
				(justify left bottom)
				(hide yes)
			)
		)
		(property "Datasheet" "https://www.bourns.com/docs/product-datasheets/cr.pdf"
			(at 254 114.3 0)
			(effects
				(font
					(size 1.27 1.27)
					(thickness 0.15)
				)
				(justify left bottom)
				(hide yes)
			)
		)
		(property "Description" ""
			(at 233.68 96.52 0)
			(effects
				(font
					(size 1.27 1.27)
				)
				(hide yes)
			)
		)
		(property "MPN" "CR0402-FX-3011GLF"
			(at 254 116.84 0)
			(effects
				(font
					(size 1.27 1.27)
					(thickness 0.15)
				)
				(justify left bottom)
				(hide yes)
			)
		)
		(property "Manufacturer" "Bourns"
			(at 254 119.38 0)
			(effects
				(font
					(size 1.27 1.27)
					(thickness 0.15)
				)
				(justify left bottom)
				(hide yes)
			)
		)
		(property "License" "Apache-2.0"
			(at 254 121.92 0)
			(effects
				(font
					(size 1.27 1.27)
					(thickness 0.15)
				)
				(justify left bottom)
				(hide yes)
			)
		)
		(property "Val" "3k01"
			(at 236.22 102.87 0)
			(effects
				(font
					(size 1.27 1.27)
					(thickness 0.15)
				)
			)
		)
		(property "Tolerance" "1%"
			(at 254 106.68 0)
			(effects
				(font
					(size 1.27 1.27)
				)
				(justify left bottom)
				(hide yes)
			)
		)
		(property "Author" "Antmicro"
			(at 254 124.46 0)
			(effects
				(font
					(size 1.27 1.27)
					(thickness 0.15)
				)
				(justify left bottom)
				(hide yes)
			)
		)
		(pin "1"
		)
		(pin "2"
		)
		(instances
			(project "thunderbolt-gpu-adapter"
				(path ""
					(reference "R74")
					(unit 1)
				)
			)
		)
	)
	(symbol
		(lib_id "antmicroResistors0402:R_100k_0402")
		(at 208.28 228.6 90)
		(unit 1)
		(exclude_from_sim no)
		(in_bom yes)
		(on_board yes)
		(dnp no)
		(fields_autoplaced yes)
		(property "Reference" "R90"
			(at 210.185 224.79 90)
			(effects
				(font
					(size 1.27 1.27)
					(thickness 0.15)
				)
				(justify right)
			)
		)
		(property "Value" "R_100k_0402"
			(at 220.98 208.28 0)
			(effects
				(font
					(size 1.27 1.27)
					(thickness 0.15)
				)
				(justify left bottom)
				(hide yes)
			)
		)
		(property "Footprint" "antmicro-footprints:R_0402_1005Metric"
			(at 223.52 208.28 0)
			(effects
				(font
					(size 1.27 1.27)
					(thickness 0.15)
				)
				(justify left bottom)
				(hide yes)
			)
		)
		(property "Datasheet" "https://www.bourns.com/docs/product-datasheets/cr.pdf"
			(at 226.06 208.28 0)
			(effects
				(font
					(size 1.27 1.27)
					(thickness 0.15)
				)
				(justify left bottom)
				(hide yes)
			)
		)
		(property "Description" ""
			(at 208.28 228.6 0)
			(effects
				(font
					(size 1.27 1.27)
				)
				(hide yes)
			)
		)
		(property "MPN" "CR0402-FX-1003GLF"
			(at 228.6 208.28 0)
			(effects
				(font
					(size 1.27 1.27)
					(thickness 0.15)
				)
				(justify left bottom)
				(hide yes)
			)
		)
		(property "Manufacturer" "Bourns"
			(at 231.14 208.28 0)
			(effects
				(font
					(size 1.27 1.27)
					(thickness 0.15)
				)
				(justify left bottom)
				(hide yes)
			)
		)
		(property "License" "Apache-2.0"
			(at 233.68 208.28 0)
			(effects
				(font
					(size 1.27 1.27)
					(thickness 0.15)
				)
				(justify left bottom)
				(hide yes)
			)
		)
		(property "Val" "100k"
			(at 210.185 227.33 90)
			(effects
				(font
					(size 1.27 1.27)
					(thickness 0.15)
				)
				(justify right)
			)
		)
		(property "Tolerance" "1%"
			(at 218.44 208.28 0)
			(effects
				(font
					(size 1.27 1.27)
				)
				(justify left bottom)
				(hide yes)
			)
		)
		(property "Author" "Antmicro"
			(at 236.22 208.28 0)
			(effects
				(font
					(size 1.27 1.27)
					(thickness 0.15)
				)
				(justify left bottom)
				(hide yes)
			)
		)
		(pin "1"
		)
		(pin "2"
		)
		(instances
			(project "thunderbolt-gpu-adapter"
				(path ""
					(reference "R90")
					(unit 1)
				)
			)
		)
	)
	(symbol
		(lib_id "antmicroCapacitors0402:C_220n_0402")
		(at 250.19 81.28 0)
		(unit 1)
		(exclude_from_sim no)
		(in_bom yes)
		(on_board yes)
		(dnp no)
		(property "Reference" "C112"
			(at 256.54 80.01 0)
			(effects
				(font
					(size 1.27 1.27)
					(thickness 0.15)
				)
			)
		)
		(property "Value" "C_220n_0402"
			(at 270.51 91.44 0)
			(effects
				(font
					(size 1.27 1.27)
					(thickness 0.15)
				)
				(justify left bottom)
				(hide yes)
			)
		)
		(property "Footprint" "antmicro-footprints:C_0402_1005Metric"
			(at 270.51 93.98 0)
			(effects
				(font
					(size 1.27 1.27)
					(thickness 0.15)
				)
				(justify left bottom)
				(hide yes)
			)
		)
		(property "Datasheet" "https://www.yageo.com/en/Chart/Download/pdf/CC0402KRX5R6BB224"
			(at 270.51 96.52 0)
			(effects
				(font
					(size 1.27 1.27)
					(thickness 0.15)
				)
				(justify left bottom)
				(hide yes)
			)
		)
		(property "Description" ""
			(at 250.19 81.28 0)
			(effects
				(font
					(size 1.27 1.27)
				)
				(hide yes)
			)
		)
		(property "MPN" "CC0402KRX5R6BB224"
			(at 270.51 99.06 0)
			(effects
				(font
					(size 1.27 1.27)
					(thickness 0.15)
				)
				(justify left bottom)
				(hide yes)
			)
		)
		(property "Manufacturer" "YAGEO"
			(at 270.51 101.6 0)
			(effects
				(font
					(size 1.27 1.27)
					(thickness 0.15)
				)
				(justify left bottom)
				(hide yes)
			)
		)
		(property "License" "Apache-2.0"
			(at 270.51 104.14 0)
			(effects
				(font
					(size 1.27 1.27)
					(thickness 0.15)
				)
				(justify left bottom)
				(hide yes)
			)
		)
		(property "Val" "220n"
			(at 256.54 82.55 0)
			(effects
				(font
					(size 1.27 1.27)
					(thickness 0.15)
				)
			)
		)
		(property "Voltage" ""
			(at 270.51 109.22 0)
			(effects
				(font
					(size 1.27 1.27)
				)
				(justify left bottom)
				(hide yes)
			)
		)
		(property "Dielectric" ""
			(at 270.51 111.76 0)
			(effects
				(font
					(size 1.27 1.27)
				)
				(justify left bottom)
				(hide yes)
			)
		)
		(property "Author" "Antmicro"
			(at 270.51 106.68 0)
			(effects
				(font
					(size 1.27 1.27)
					(thickness 0.15)
				)
				(justify left bottom)
				(hide yes)
			)
		)
		(pin "1"
		)
		(pin "2"
		)
		(instances
			(project "thunderbolt-gpu-adapter"
				(path ""
					(reference "C112")
					(unit 1)
				)
			)
		)
	)
	(symbol
		(lib_id "antmicroResistors0402:R_2k2_0402")
		(at 114.3 186.69 0)
		(unit 1)
		(exclude_from_sim no)
		(in_bom yes)
		(on_board yes)
		(dnp no)
		(property "Reference" "R58"
			(at 116.84 184.785 0)
			(effects
				(font
					(size 1.27 1.27)
					(thickness 0.15)
				)
			)
		)
		(property "Value" "R_2k2_0402"
			(at 134.62 199.39 0)
			(effects
				(font
					(size 1.27 1.27)
					(thickness 0.15)
				)
				(justify left bottom)
				(hide yes)
			)
		)
		(property "Footprint" "antmicro-footprints:R_0402_1005Metric"
			(at 134.62 201.93 0)
			(effects
				(font
					(size 1.27 1.27)
					(thickness 0.15)
				)
				(justify left bottom)
				(hide yes)
			)
		)
		(property "Datasheet" "https://www.bourns.com/docs/product-datasheets/cr.pdf"
			(at 134.62 204.47 0)
			(effects
				(font
					(size 1.27 1.27)
					(thickness 0.15)
				)
				(justify left bottom)
				(hide yes)
			)
		)
		(property "Description" ""
			(at 114.3 186.69 0)
			(effects
				(font
					(size 1.27 1.27)
				)
				(hide yes)
			)
		)
		(property "MPN" "CR0402-FX-2201GLF"
			(at 134.62 207.01 0)
			(effects
				(font
					(size 1.27 1.27)
					(thickness 0.15)
				)
				(justify left bottom)
				(hide yes)
			)
		)
		(property "Manufacturer" "Bourns"
			(at 134.62 209.55 0)
			(effects
				(font
					(size 1.27 1.27)
					(thickness 0.15)
				)
				(justify left bottom)
				(hide yes)
			)
		)
		(property "License" "Apache-2.0"
			(at 134.62 212.09 0)
			(effects
				(font
					(size 1.27 1.27)
					(thickness 0.15)
				)
				(justify left bottom)
				(hide yes)
			)
		)
		(property "Val" "2k2"
			(at 120.65 185.42 0)
			(effects
				(font
					(size 1.27 1.27)
					(thickness 0.15)
				)
			)
		)
		(property "Tolerance" "1%"
			(at 134.62 196.85 0)
			(effects
				(font
					(size 1.27 1.27)
				)
				(justify left bottom)
				(hide yes)
			)
		)
		(property "Author" "Antmicro"
			(at 134.62 214.63 0)
			(effects
				(font
					(size 1.27 1.27)
					(thickness 0.15)
				)
				(justify left bottom)
				(hide yes)
			)
		)
		(pin "1"
		)
		(pin "2"
		)
		(instances
			(project "thunderbolt-gpu-adapter"
				(path ""
					(reference "R58")
					(unit 1)
				)
			)
		)
	)
	(symbol
		(lib_id "antmicroResistors0402:R_2k2_0402")
		(at 114.3 242.57 0)
		(unit 1)
		(exclude_from_sim no)
		(in_bom yes)
		(on_board yes)
		(dnp no)
		(property "Reference" "R62"
			(at 116.84 244.475 0)
			(effects
				(font
					(size 1.27 1.27)
					(thickness 0.15)
				)
			)
		)
		(property "Value" "R_2k2_0402"
			(at 134.62 255.27 0)
			(effects
				(font
					(size 1.27 1.27)
					(thickness 0.15)
				)
				(justify left bottom)
				(hide yes)
			)
		)
		(property "Footprint" "antmicro-footprints:R_0402_1005Metric"
			(at 134.62 257.81 0)
			(effects
				(font
					(size 1.27 1.27)
					(thickness 0.15)
				)
				(justify left bottom)
				(hide yes)
			)
		)
		(property "Datasheet" "https://www.bourns.com/docs/product-datasheets/cr.pdf"
			(at 134.62 260.35 0)
			(effects
				(font
					(size 1.27 1.27)
					(thickness 0.15)
				)
				(justify left bottom)
				(hide yes)
			)
		)
		(property "Description" ""
			(at 114.3 242.57 0)
			(effects
				(font
					(size 1.27 1.27)
				)
				(hide yes)
			)
		)
		(property "MPN" "CR0402-FX-2201GLF"
			(at 134.62 262.89 0)
			(effects
				(font
					(size 1.27 1.27)
					(thickness 0.15)
				)
				(justify left bottom)
				(hide yes)
			)
		)
		(property "Manufacturer" "Bourns"
			(at 134.62 265.43 0)
			(effects
				(font
					(size 1.27 1.27)
					(thickness 0.15)
				)
				(justify left bottom)
				(hide yes)
			)
		)
		(property "License" "Apache-2.0"
			(at 134.62 267.97 0)
			(effects
				(font
					(size 1.27 1.27)
					(thickness 0.15)
				)
				(justify left bottom)
				(hide yes)
			)
		)
		(property "Val" "2k2"
			(at 120.65 243.84 0)
			(effects
				(font
					(size 1.27 1.27)
					(thickness 0.15)
				)
			)
		)
		(property "Tolerance" "1%"
			(at 134.62 252.73 0)
			(effects
				(font
					(size 1.27 1.27)
				)
				(justify left bottom)
				(hide yes)
			)
		)
		(property "Author" "Antmicro"
			(at 134.62 270.51 0)
			(effects
				(font
					(size 1.27 1.27)
					(thickness 0.15)
				)
				(justify left bottom)
				(hide yes)
			)
		)
		(pin "1"
		)
		(pin "2"
		)
		(instances
			(project "thunderbolt-gpu-adapter"
				(path ""
					(reference "R62")
					(unit 1)
				)
			)
		)
	)
	(symbol
		(lib_id "antmicropower:GND")
		(at 187.96 356.87 270)
		(unit 1)
		(exclude_from_sim no)
		(in_bom yes)
		(on_board yes)
		(dnp no)
		(property "Reference" "#PWR0137"
			(at 181.61 356.87 0)
			(effects
				(font
					(size 1.27 1.27)
				)
				(hide yes)
			)
		)
		(property "Value" "GND"
			(at 184.15 356.87 0)
			(effects
				(font
					(size 1.27 1.27)
				)
			)
		)
		(property "Footprint" ""
			(at 187.96 356.87 0)
			(effects
				(font
					(size 1.27 1.27)
				)
				(hide yes)
			)
		)
		(property "Datasheet" ""
			(at 187.96 356.87 0)
			(effects
				(font
					(size 1.27 1.27)
				)
				(hide yes)
			)
		)
		(property "Description" ""
			(at 187.96 356.87 0)
			(effects
				(font
					(size 1.27 1.27)
				)
				(hide yes)
			)
		)
		(property "Author" "Antmicro"
			(at 180.34 365.76 0)
			(effects
				(font
					(size 1.27 1.27)
					(thickness 0.15)
				)
				(justify left bottom)
				(hide yes)
			)
		)
		(property "License" "Apache-2.0"
			(at 177.8 365.76 0)
			(effects
				(font
					(size 1.27 1.27)
					(thickness 0.15)
				)
				(justify left bottom)
				(hide yes)
			)
		)
		(pin "1"
		)
		(instances
			(project "thunderbolt-gpu-adapter"
				(path ""
					(reference "#PWR0137")
					(unit 1)
				)
			)
		)
	)
	(symbol
		(lib_id "antmicroMemory:MX25L8006EM2I-12G")
		(at 101.6 372.11 0)
		(mirror y)
		(unit 1)
		(exclude_from_sim no)
		(in_bom yes)
		(on_board yes)
		(dnp yes)
		(fields_autoplaced yes)
		(property "Reference" "U7"
			(at 88.9 365.125 0)
			(effects
				(font
					(size 1.27 1.27)
					(thickness 0.15)
				)
			)
		)
		(property "Value" "MX25L8006EM2I-12G"
			(at 66.04 374.65 0)
			(effects
				(font
					(size 1.27 1.27)
					(thickness 0.15)
				)
				(justify left bottom)
				(hide yes)
			)
		)
		(property "Footprint" "antmicro-footprints:SOIC-8_5.3x5.3x2mm_P1.27mm"
			(at 66.04 377.19 0)
			(effects
				(font
					(size 1.27 1.27)
					(thickness 0.15)
				)
				(justify left bottom)
				(hide yes)
			)
		)
		(property "Datasheet" "https://www.macronix.com/Lists/Datasheet/Attachments/8680/MX25L8006E,%203V,%208Mb,%20v1.6.pdf"
			(at 66.04 379.73 0)
			(effects
				(font
					(size 1.27 1.27)
					(thickness 0.15)
				)
				(justify left bottom)
				(hide yes)
			)
		)
		(property "Description" ""
			(at 101.6 372.11 0)
			(effects
				(font
					(size 1.27 1.27)
				)
				(hide yes)
			)
		)
		(property "MPN" "MX25L8006EM2I-12G"
			(at 88.9 367.665 0)
			(effects
				(font
					(size 1.27 1.27)
					(thickness 0.15)
				)
			)
		)
		(property "Manufacturer" "Macronix"
			(at 66.04 384.81 0)
			(effects
				(font
					(size 1.27 1.27)
					(thickness 0.15)
				)
				(justify left bottom)
				(hide yes)
			)
		)
		(property "Author" "Antmicro"
			(at 66.04 387.35 0)
			(effects
				(font
					(size 1.27 1.27)
					(thickness 0.15)
				)
				(justify left bottom)
				(hide yes)
			)
		)
		(property "License" "Apache-2.0"
			(at 66.04 389.89 0)
			(effects
				(font
					(size 1.27 1.27)
					(thickness 0.15)
				)
				(justify left bottom)
				(hide yes)
			)
		)
		(pin "1"
		)
		(pin "2"
		)
		(pin "3"
		)
		(pin "4"
		)
		(pin "5"
		)
		(pin "6"
		)
		(pin "7"
		)
		(pin "8"
		)
		(instances
			(project "thunderbolt-gpu-adapter"
				(path ""
					(reference "U7")
					(unit 1)
				)
			)
		)
	)
	(symbol
		(lib_id "antmicroCapacitors0402:C_10p_0402")
		(at 190.5 368.3 0)
		(unit 1)
		(exclude_from_sim no)
		(in_bom yes)
		(on_board yes)
		(dnp no)
		(fields_autoplaced yes)
		(property "Reference" "C114"
			(at 193.0463 372.745 0)
			(effects
				(font
					(size 1.27 1.27)
					(thickness 0.15)
				)
			)
		)
		(property "Value" "C_10p_0402"
			(at 210.82 378.46 0)
			(effects
				(font
					(size 1.27 1.27)
					(thickness 0.15)
				)
				(justify left bottom)
				(hide yes)
			)
		)
		(property "Footprint" "antmicro-footprints:C_0402_1005Metric"
			(at 210.82 381 0)
			(effects
				(font
					(size 1.27 1.27)
					(thickness 0.15)
				)
				(justify left bottom)
				(hide yes)
			)
		)
		(property "Datasheet" "https://www.murata.com/products/productdetail?partno=GCM1555C1H100GA16%23"
			(at 210.82 383.54 0)
			(effects
				(font
					(size 1.27 1.27)
					(thickness 0.15)
				)
				(justify left bottom)
				(hide yes)
			)
		)
		(property "Description" ""
			(at 190.5 368.3 0)
			(effects
				(font
					(size 1.27 1.27)
				)
				(hide yes)
			)
		)
		(property "MPN" "GCM1555C1H100GA16D"
			(at 210.82 386.08 0)
			(effects
				(font
					(size 1.27 1.27)
					(thickness 0.15)
				)
				(justify left bottom)
				(hide yes)
			)
		)
		(property "Manufacturer" "Murata"
			(at 210.82 388.62 0)
			(effects
				(font
					(size 1.27 1.27)
					(thickness 0.15)
				)
				(justify left bottom)
				(hide yes)
			)
		)
		(property "License" "Apache-2.0"
			(at 210.82 391.16 0)
			(effects
				(font
					(size 1.27 1.27)
					(thickness 0.15)
				)
				(justify left bottom)
				(hide yes)
			)
		)
		(property "Val" "10p"
			(at 193.0463 375.285 0)
			(effects
				(font
					(size 1.27 1.27)
					(thickness 0.15)
				)
			)
		)
		(property "Voltage" "50V"
			(at 210.82 396.24 0)
			(effects
				(font
					(size 1.27 1.27)
				)
				(justify left bottom)
				(hide yes)
			)
		)
		(property "Dielectric" "C0G"
			(at 210.82 398.78 0)
			(effects
				(font
					(size 1.27 1.27)
				)
				(justify left bottom)
				(hide yes)
			)
		)
		(property "Author" "Antmicro"
			(at 210.82 393.7 0)
			(effects
				(font
					(size 1.27 1.27)
					(thickness 0.15)
				)
				(justify left bottom)
				(hide yes)
			)
		)
		(pin "1"
		)
		(pin "2"
		)
		(instances
			(project "thunderbolt-gpu-adapter"
				(path ""
					(reference "C114")
					(unit 1)
				)
			)
		)
	)
	(symbol
		(lib_id "antmicropower:GND")
		(at 73.66 384.81 0)
		(unit 1)
		(exclude_from_sim no)
		(in_bom yes)
		(on_board yes)
		(dnp no)
		(property "Reference" "#PWR0128"
			(at 73.66 391.16 0)
			(effects
				(font
					(size 1.27 1.27)
				)
				(hide yes)
			)
		)
		(property "Value" "GND"
			(at 73.66 388.62 0)
			(effects
				(font
					(size 1.27 1.27)
				)
			)
		)
		(property "Footprint" ""
			(at 73.66 384.81 0)
			(effects
				(font
					(size 1.27 1.27)
				)
				(hide yes)
			)
		)
		(property "Datasheet" ""
			(at 73.66 384.81 0)
			(effects
				(font
					(size 1.27 1.27)
				)
				(hide yes)
			)
		)
		(property "Description" ""
			(at 73.66 384.81 0)
			(effects
				(font
					(size 1.27 1.27)
				)
				(hide yes)
			)
		)
		(property "Author" "Antmicro"
			(at 82.55 392.43 0)
			(effects
				(font
					(size 1.27 1.27)
					(thickness 0.15)
				)
				(justify left bottom)
				(hide yes)
			)
		)
		(property "License" "Apache-2.0"
			(at 82.55 394.97 0)
			(effects
				(font
					(size 1.27 1.27)
					(thickness 0.15)
				)
				(justify left bottom)
				(hide yes)
			)
		)
		(pin "1"
		)
		(instances
			(project "thunderbolt-gpu-adapter"
				(path ""
					(reference "#PWR0128")
					(unit 1)
				)
			)
		)
	)
	(symbol
		(lib_id "antmicroCapacitors0402:C_220n_0402")
		(at 243.84 60.96 0)
		(unit 1)
		(exclude_from_sim no)
		(in_bom yes)
		(on_board yes)
		(dnp no)
		(property "Reference" "C105"
			(at 242.57 59.69 0)
			(effects
				(font
					(size 1.27 1.27)
					(thickness 0.15)
				)
			)
		)
		(property "Value" "C_220n_0402"
			(at 264.16 71.12 0)
			(effects
				(font
					(size 1.27 1.27)
					(thickness 0.15)
				)
				(justify left bottom)
				(hide yes)
			)
		)
		(property "Footprint" "antmicro-footprints:C_0402_1005Metric"
			(at 264.16 73.66 0)
			(effects
				(font
					(size 1.27 1.27)
					(thickness 0.15)
				)
				(justify left bottom)
				(hide yes)
			)
		)
		(property "Datasheet" "https://www.yageo.com/en/Chart/Download/pdf/CC0402KRX5R6BB224"
			(at 264.16 76.2 0)
			(effects
				(font
					(size 1.27 1.27)
					(thickness 0.15)
				)
				(justify left bottom)
				(hide yes)
			)
		)
		(property "Description" ""
			(at 243.84 60.96 0)
			(effects
				(font
					(size 1.27 1.27)
				)
				(hide yes)
			)
		)
		(property "MPN" "CC0402KRX5R6BB224"
			(at 264.16 78.74 0)
			(effects
				(font
					(size 1.27 1.27)
					(thickness 0.15)
				)
				(justify left bottom)
				(hide yes)
			)
		)
		(property "Manufacturer" "YAGEO"
			(at 264.16 81.28 0)
			(effects
				(font
					(size 1.27 1.27)
					(thickness 0.15)
				)
				(justify left bottom)
				(hide yes)
			)
		)
		(property "License" "Apache-2.0"
			(at 264.16 83.82 0)
			(effects
				(font
					(size 1.27 1.27)
					(thickness 0.15)
				)
				(justify left bottom)
				(hide yes)
			)
		)
		(property "Val" "220n"
			(at 242.57 62.23 0)
			(effects
				(font
					(size 1.27 1.27)
					(thickness 0.15)
				)
			)
		)
		(property "Voltage" ""
			(at 264.16 88.9 0)
			(effects
				(font
					(size 1.27 1.27)
				)
				(justify left bottom)
				(hide yes)
			)
		)
		(property "Dielectric" ""
			(at 264.16 91.44 0)
			(effects
				(font
					(size 1.27 1.27)
				)
				(justify left bottom)
				(hide yes)
			)
		)
		(property "Author" "Antmicro"
			(at 264.16 86.36 0)
			(effects
				(font
					(size 1.27 1.27)
					(thickness 0.15)
				)
				(justify left bottom)
				(hide yes)
			)
		)
		(pin "1"
		)
		(pin "2"
		)
		(instances
			(project "thunderbolt-gpu-adapter"
				(path ""
					(reference "C105")
					(unit 1)
				)
			)
		)
	)
	(symbol
		(lib_id "antmicroCapacitors0402:C_220n_0402")
		(at 44.45 66.04 0)
		(unit 1)
		(exclude_from_sim no)
		(in_bom yes)
		(on_board yes)
		(dnp no)
		(property "Reference" "C102"
			(at 50.165 64.77 0)
			(effects
				(font
					(size 1.27 1.27)
					(thickness 0.15)
				)
			)
		)
		(property "Value" "C_220n_0402"
			(at 64.77 76.2 0)
			(effects
				(font
					(size 1.27 1.27)
					(thickness 0.15)
				)
				(justify left bottom)
				(hide yes)
			)
		)
		(property "Footprint" "antmicro-footprints:C_0402_1005Metric"
			(at 64.77 78.74 0)
			(effects
				(font
					(size 1.27 1.27)
					(thickness 0.15)
				)
				(justify left bottom)
				(hide yes)
			)
		)
		(property "Datasheet" "https://www.yageo.com/en/Chart/Download/pdf/CC0402KRX5R6BB224"
			(at 64.77 81.28 0)
			(effects
				(font
					(size 1.27 1.27)
					(thickness 0.15)
				)
				(justify left bottom)
				(hide yes)
			)
		)
		(property "Description" ""
			(at 44.45 66.04 0)
			(effects
				(font
					(size 1.27 1.27)
				)
				(hide yes)
			)
		)
		(property "MPN" "CC0402KRX5R6BB224"
			(at 64.77 83.82 0)
			(effects
				(font
					(size 1.27 1.27)
					(thickness 0.15)
				)
				(justify left bottom)
				(hide yes)
			)
		)
		(property "Manufacturer" "YAGEO"
			(at 64.77 86.36 0)
			(effects
				(font
					(size 1.27 1.27)
					(thickness 0.15)
				)
				(justify left bottom)
				(hide yes)
			)
		)
		(property "License" "Apache-2.0"
			(at 64.77 88.9 0)
			(effects
				(font
					(size 1.27 1.27)
					(thickness 0.15)
				)
				(justify left bottom)
				(hide yes)
			)
		)
		(property "Val" "220n"
			(at 50.165 67.31 0)
			(effects
				(font
					(size 1.27 1.27)
					(thickness 0.15)
				)
			)
		)
		(property "Voltage" ""
			(at 64.77 93.98 0)
			(effects
				(font
					(size 1.27 1.27)
				)
				(justify left bottom)
				(hide yes)
			)
		)
		(property "Dielectric" ""
			(at 64.77 96.52 0)
			(effects
				(font
					(size 1.27 1.27)
				)
				(justify left bottom)
				(hide yes)
			)
		)
		(property "Author" "Antmicro"
			(at 64.77 91.44 0)
			(effects
				(font
					(size 1.27 1.27)
					(thickness 0.15)
				)
				(justify left bottom)
				(hide yes)
			)
		)
		(pin "1"
		)
		(pin "2"
		)
		(instances
			(project "thunderbolt-gpu-adapter"
				(path ""
					(reference "C102")
					(unit 1)
				)
			)
		)
	)
	(symbol
		(lib_id "antmicroResonators:Resonator_25MHz_ABM8G")
		(at 139.7 297.18 90)
		(unit 1)
		(exclude_from_sim no)
		(in_bom yes)
		(on_board yes)
		(dnp no)
		(fields_autoplaced yes)
		(property "Reference" "Y2"
			(at 135.89 292.1 90)
			(effects
				(font
					(size 1.27 1.27)
					(thickness 0.15)
				)
				(justify left)
			)
		)
		(property "Value" "Resonator_25MHz_ABM8G"
			(at 152.4 281.94 0)
			(effects
				(font
					(size 1.27 1.27)
					(thickness 0.15)
				)
				(justify left bottom)
				(hide yes)
			)
		)
		(property "Footprint" "antmicro-footprints:Resonator_SMD_Abracon_ABM8G_3.2x2.5mm"
			(at 154.94 281.94 0)
			(effects
				(font
					(size 1.27 1.27)
					(thickness 0.15)
				)
				(justify left bottom)
				(hide yes)
			)
		)
		(property "Datasheet" "https://abracon.com/Resonators/ABM8G.pdf"
			(at 157.48 281.94 0)
			(effects
				(font
					(size 1.27 1.27)
					(thickness 0.15)
				)
				(justify left bottom)
				(hide yes)
			)
		)
		(property "Description" ""
			(at 139.7 297.18 0)
			(effects
				(font
					(size 1.27 1.27)
				)
				(hide yes)
			)
		)
		(property "MPN" "ABM8G-25.000MHZ-18-D2Y-T3"
			(at 135.89 293.37 90)
			(effects
				(font
					(size 1.27 1.27)
					(thickness 0.15)
				)
				(justify left)
				(hide yes)
			)
		)
		(property "Manufacturer" "Abracon"
			(at 160.02 281.94 0)
			(effects
				(font
					(size 1.27 1.27)
					(thickness 0.15)
				)
				(justify left bottom)
				(hide yes)
			)
		)
		(property "License" "Apache-2.0"
			(at 165.1 281.94 0)
			(effects
				(font
					(size 1.27 1.27)
					(thickness 0.15)
				)
				(justify left bottom)
				(hide yes)
			)
		)
		(property "Author" "Antmicro"
			(at 162.56 281.94 0)
			(effects
				(font
					(size 1.27 1.27)
					(thickness 0.15)
				)
				(justify left bottom)
				(hide yes)
			)
		)
		(property "Val" "25 MHz"
			(at 135.89 294.64 90)
			(effects
				(font
					(size 1.27 1.27)
					(thickness 0.15)
				)
				(justify left)
			)
		)
		(pin "1"
		)
		(pin "2"
		)
		(pin "3"
		)
		(pin "4"
		)
		(instances
			(project "thunderbolt-gpu-adapter"
				(path ""
					(reference "Y2")
					(unit 1)
				)
			)
		)
	)
	(symbol
		(lib_id "antmicroResistors0402:R_3k3_0402")
		(at 106.68 365.76 90)
		(unit 1)
		(exclude_from_sim no)
		(in_bom yes)
		(on_board yes)
		(dnp no)
		(fields_autoplaced yes)
		(property "Reference" "R50"
			(at 108.585 361.95 90)
			(effects
				(font
					(size 1.27 1.27)
					(thickness 0.15)
				)
				(justify right)
			)
		)
		(property "Value" "R_3k3_0402"
			(at 119.38 345.44 0)
			(effects
				(font
					(size 1.27 1.27)
					(thickness 0.15)
				)
				(justify left bottom)
				(hide yes)
			)
		)
		(property "Footprint" "antmicro-footprints:R_0402_1005Metric"
			(at 121.92 345.44 0)
			(effects
				(font
					(size 1.27 1.27)
					(thickness 0.15)
				)
				(justify left bottom)
				(hide yes)
			)
		)
		(property "Datasheet" "https://www.bourns.com/docs/product-datasheets/cr.pdf"
			(at 124.46 345.44 0)
			(effects
				(font
					(size 1.27 1.27)
					(thickness 0.15)
				)
				(justify left bottom)
				(hide yes)
			)
		)
		(property "Description" ""
			(at 106.68 365.76 0)
			(effects
				(font
					(size 1.27 1.27)
				)
				(hide yes)
			)
		)
		(property "MPN" "CR0402-FX-3301GLF"
			(at 127 345.44 0)
			(effects
				(font
					(size 1.27 1.27)
					(thickness 0.15)
				)
				(justify left bottom)
				(hide yes)
			)
		)
		(property "Manufacturer" "Bourns"
			(at 129.54 345.44 0)
			(effects
				(font
					(size 1.27 1.27)
					(thickness 0.15)
				)
				(justify left bottom)
				(hide yes)
			)
		)
		(property "License" "Apache-2.0"
			(at 132.08 345.44 0)
			(effects
				(font
					(size 1.27 1.27)
					(thickness 0.15)
				)
				(justify left bottom)
				(hide yes)
			)
		)
		(property "Val" "3k3"
			(at 108.585 364.49 90)
			(effects
				(font
					(size 1.27 1.27)
					(thickness 0.15)
				)
				(justify right)
			)
		)
		(property "Tolerance" "1%"
			(at 116.84 345.44 0)
			(effects
				(font
					(size 1.27 1.27)
				)
				(justify left bottom)
				(hide yes)
			)
		)
		(property "Author" "Antmicro"
			(at 134.62 345.44 0)
			(effects
				(font
					(size 1.27 1.27)
					(thickness 0.15)
				)
				(justify left bottom)
				(hide yes)
			)
		)
		(pin "1"
		)
		(pin "2"
		)
		(instances
			(project "thunderbolt-gpu-adapter"
				(path ""
					(reference "R50")
					(unit 1)
				)
			)
		)
	)
	(symbol
		(lib_id "antmicropower:GND")
		(at 194.31 187.96 0)
		(unit 1)
		(exclude_from_sim no)
		(in_bom yes)
		(on_board yes)
		(dnp no)
		(property "Reference" "#PWR0142"
			(at 194.31 194.31 0)
			(effects
				(font
					(size 1.27 1.27)
				)
				(hide yes)
			)
		)
		(property "Value" "GND"
			(at 194.31 191.77 0)
			(effects
				(font
					(size 1.27 1.27)
				)
			)
		)
		(property "Footprint" ""
			(at 194.31 187.96 0)
			(effects
				(font
					(size 1.27 1.27)
				)
				(hide yes)
			)
		)
		(property "Datasheet" ""
			(at 194.31 187.96 0)
			(effects
				(font
					(size 1.27 1.27)
				)
				(hide yes)
			)
		)
		(property "Description" ""
			(at 194.31 187.96 0)
			(effects
				(font
					(size 1.27 1.27)
				)
				(hide yes)
			)
		)
		(property "Author" "Antmicro"
			(at 203.2 195.58 0)
			(effects
				(font
					(size 1.27 1.27)
					(thickness 0.15)
				)
				(justify left bottom)
				(hide yes)
			)
		)
		(property "License" "Apache-2.0"
			(at 203.2 198.12 0)
			(effects
				(font
					(size 1.27 1.27)
					(thickness 0.15)
				)
				(justify left bottom)
				(hide yes)
			)
		)
		(pin "1"
		)
		(instances
			(project "thunderbolt-gpu-adapter"
				(path ""
					(reference "#PWR0142")
					(unit 1)
				)
			)
		)
	)
	(symbol
		(lib_id "antmicroResistors0402:R_100k_0402")
		(at 182.88 227.33 0)
		(unit 1)
		(exclude_from_sim no)
		(in_bom yes)
		(on_board yes)
		(dnp no)
		(property "Reference" "R84"
			(at 181.61 226.06 0)
			(effects
				(font
					(size 1.27 1.27)
					(thickness 0.15)
				)
			)
		)
		(property "Value" "R_100k_0402"
			(at 203.2 240.03 0)
			(effects
				(font
					(size 1.27 1.27)
					(thickness 0.15)
				)
				(justify left bottom)
				(hide yes)
			)
		)
		(property "Footprint" "antmicro-footprints:R_0402_1005Metric"
			(at 203.2 242.57 0)
			(effects
				(font
					(size 1.27 1.27)
					(thickness 0.15)
				)
				(justify left bottom)
				(hide yes)
			)
		)
		(property "Datasheet" "https://www.bourns.com/docs/product-datasheets/cr.pdf"
			(at 203.2 245.11 0)
			(effects
				(font
					(size 1.27 1.27)
					(thickness 0.15)
				)
				(justify left bottom)
				(hide yes)
			)
		)
		(property "Description" ""
			(at 182.88 227.33 0)
			(effects
				(font
					(size 1.27 1.27)
				)
				(hide yes)
			)
		)
		(property "MPN" "CR0402-FX-1003GLF"
			(at 203.2 247.65 0)
			(effects
				(font
					(size 1.27 1.27)
					(thickness 0.15)
				)
				(justify left bottom)
				(hide yes)
			)
		)
		(property "Manufacturer" "Bourns"
			(at 203.2 250.19 0)
			(effects
				(font
					(size 1.27 1.27)
					(thickness 0.15)
				)
				(justify left bottom)
				(hide yes)
			)
		)
		(property "License" "Apache-2.0"
			(at 203.2 252.73 0)
			(effects
				(font
					(size 1.27 1.27)
					(thickness 0.15)
				)
				(justify left bottom)
				(hide yes)
			)
		)
		(property "Val" "100k"
			(at 189.865 226.06 0)
			(effects
				(font
					(size 1.27 1.27)
					(thickness 0.15)
				)
			)
		)
		(property "Tolerance" "1%"
			(at 203.2 237.49 0)
			(effects
				(font
					(size 1.27 1.27)
				)
				(justify left bottom)
				(hide yes)
			)
		)
		(property "Author" "Antmicro"
			(at 203.2 255.27 0)
			(effects
				(font
					(size 1.27 1.27)
					(thickness 0.15)
				)
				(justify left bottom)
				(hide yes)
			)
		)
		(pin "1"
		)
		(pin "2"
		)
		(instances
			(project "thunderbolt-gpu-adapter"
				(path ""
					(reference "R84")
					(unit 1)
				)
			)
		)
	)
	(symbol
		(lib_id "antmicroMemory:MX25L8006EM1I-12G")
		(at 45.72 372.11 0)
		(unit 1)
		(exclude_from_sim no)
		(in_bom yes)
		(on_board yes)
		(dnp no)
		(fields_autoplaced yes)
		(property "Reference" "U5"
			(at 58.42 365.125 0)
			(effects
				(font
					(size 1.27 1.27)
					(thickness 0.15)
				)
			)
		)
		(property "Value" "MX25L8006EM1I-12G"
			(at 81.28 374.65 0)
			(effects
				(font
					(size 1.27 1.27)
					(thickness 0.15)
				)
				(justify left bottom)
				(hide yes)
			)
		)
		(property "Footprint" "antmicro-footprints:SOIC-8_3.9x4.9x1.75mm_P1.27mm"
			(at 81.28 377.19 0)
			(effects
				(font
					(size 1.27 1.27)
					(thickness 0.15)
				)
				(justify left bottom)
				(hide yes)
			)
		)
		(property "Datasheet" "https://www.macronix.com/Lists/Datasheet/Attachments/8680/MX25L8006E,%203V,%208Mb,%20v1.6.pdf"
			(at 81.28 379.73 0)
			(effects
				(font
					(size 1.27 1.27)
					(thickness 0.15)
				)
				(justify left bottom)
				(hide yes)
			)
		)
		(property "Description" ""
			(at 45.72 372.11 0)
			(effects
				(font
					(size 1.27 1.27)
				)
				(hide yes)
			)
		)
		(property "MPN" "MX25L8006EM1I-12G"
			(at 58.42 367.665 0)
			(effects
				(font
					(size 1.27 1.27)
					(thickness 0.15)
				)
			)
		)
		(property "Manufacturer" "Macronix"
			(at 81.28 384.81 0)
			(effects
				(font
					(size 1.27 1.27)
					(thickness 0.15)
				)
				(justify left bottom)
				(hide yes)
			)
		)
		(property "License" "Apache-2.0"
			(at 81.28 389.89 0)
			(effects
				(font
					(size 1.27 1.27)
					(thickness 0.15)
				)
				(justify left bottom)
				(hide yes)
			)
		)
		(property "Author" "Antmicro"
			(at 81.28 387.35 0)
			(effects
				(font
					(size 1.27 1.27)
					(thickness 0.15)
				)
				(justify left bottom)
				(hide yes)
			)
		)
		(pin "1"
		)
		(pin "2"
		)
		(pin "3"
		)
		(pin "4"
		)
		(pin "5"
		)
		(pin "6"
		)
		(pin "7"
		)
		(pin "8"
		)
		(instances
			(project "thunderbolt-gpu-adapter"
				(path ""
					(reference "U5")
					(unit 1)
				)
			)
		)
	)
	(symbol
		(lib_id "antmicroCapacitors0402:C_10p_0402")
		(at 142.24 299.72 0)
		(unit 1)
		(exclude_from_sim no)
		(in_bom yes)
		(on_board yes)
		(dnp no)
		(fields_autoplaced yes)
		(property "Reference" "C117"
			(at 144.7863 304.165 0)
			(effects
				(font
					(size 1.27 1.27)
					(thickness 0.15)
				)
			)
		)
		(property "Value" "C_10p_0402"
			(at 162.56 309.88 0)
			(effects
				(font
					(size 1.27 1.27)
					(thickness 0.15)
				)
				(justify left bottom)
				(hide yes)
			)
		)
		(property "Footprint" "antmicro-footprints:C_0402_1005Metric"
			(at 162.56 312.42 0)
			(effects
				(font
					(size 1.27 1.27)
					(thickness 0.15)
				)
				(justify left bottom)
				(hide yes)
			)
		)
		(property "Datasheet" "https://www.murata.com/products/productdetail?partno=GCM1555C1H100GA16%23"
			(at 162.56 314.96 0)
			(effects
				(font
					(size 1.27 1.27)
					(thickness 0.15)
				)
				(justify left bottom)
				(hide yes)
			)
		)
		(property "Description" ""
			(at 142.24 299.72 0)
			(effects
				(font
					(size 1.27 1.27)
				)
				(hide yes)
			)
		)
		(property "MPN" "GCM1555C1H100GA16D"
			(at 162.56 317.5 0)
			(effects
				(font
					(size 1.27 1.27)
					(thickness 0.15)
				)
				(justify left bottom)
				(hide yes)
			)
		)
		(property "Manufacturer" "Murata"
			(at 162.56 320.04 0)
			(effects
				(font
					(size 1.27 1.27)
					(thickness 0.15)
				)
				(justify left bottom)
				(hide yes)
			)
		)
		(property "License" "Apache-2.0"
			(at 162.56 322.58 0)
			(effects
				(font
					(size 1.27 1.27)
					(thickness 0.15)
				)
				(justify left bottom)
				(hide yes)
			)
		)
		(property "Val" "10p"
			(at 144.7863 306.705 0)
			(effects
				(font
					(size 1.27 1.27)
					(thickness 0.15)
				)
			)
		)
		(property "Voltage" "50V"
			(at 162.56 327.66 0)
			(effects
				(font
					(size 1.27 1.27)
				)
				(justify left bottom)
				(hide yes)
			)
		)
		(property "Dielectric" "C0G"
			(at 162.56 330.2 0)
			(effects
				(font
					(size 1.27 1.27)
				)
				(justify left bottom)
				(hide yes)
			)
		)
		(property "Author" "Antmicro"
			(at 162.56 325.12 0)
			(effects
				(font
					(size 1.27 1.27)
					(thickness 0.15)
				)
				(justify left bottom)
				(hide yes)
			)
		)
		(pin "1"
		)
		(pin "2"
		)
		(instances
			(project "thunderbolt-gpu-adapter"
				(path ""
					(reference "C117")
					(unit 1)
				)
			)
		)
	)
	(symbol
		(lib_id "antmicropower:GND")
		(at 60.96 105.41 0)
		(mirror y)
		(unit 1)
		(exclude_from_sim no)
		(in_bom yes)
		(on_board yes)
		(dnp no)
		(property "Reference" "#PWR0134"
			(at 60.96 111.76 0)
			(effects
				(font
					(size 1.27 1.27)
				)
				(hide yes)
			)
		)
		(property "Value" "GND"
			(at 60.96 109.22 0)
			(effects
				(font
					(size 1.27 1.27)
				)
			)
		)
		(property "Footprint" ""
			(at 60.96 105.41 0)
			(effects
				(font
					(size 1.27 1.27)
				)
				(hide yes)
			)
		)
		(property "Datasheet" ""
			(at 60.96 105.41 0)
			(effects
				(font
					(size 1.27 1.27)
				)
				(hide yes)
			)
		)
		(property "Description" ""
			(at 60.96 105.41 0)
			(effects
				(font
					(size 1.27 1.27)
				)
				(hide yes)
			)
		)
		(property "Author" "Antmicro"
			(at 52.07 113.03 0)
			(effects
				(font
					(size 1.27 1.27)
					(thickness 0.15)
				)
				(justify left bottom)
				(hide yes)
			)
		)
		(property "License" "Apache-2.0"
			(at 52.07 115.57 0)
			(effects
				(font
					(size 1.27 1.27)
					(thickness 0.15)
				)
				(justify left bottom)
				(hide yes)
			)
		)
		(pin "1"
		)
		(instances
			(project "thunderbolt-gpu-adapter"
				(path ""
					(reference "#PWR0134")
					(unit 1)
				)
			)
		)
	)
	(symbol
		(lib_id "antmicropower:GND")
		(at 46.99 107.95 0)
		(unit 1)
		(exclude_from_sim no)
		(in_bom yes)
		(on_board yes)
		(dnp no)
		(property "Reference" "#PWR0130"
			(at 46.99 114.3 0)
			(effects
				(font
					(size 1.27 1.27)
				)
				(hide yes)
			)
		)
		(property "Value" "GND"
			(at 46.99 111.76 0)
			(effects
				(font
					(size 1.27 1.27)
				)
			)
		)
		(property "Footprint" ""
			(at 46.99 107.95 0)
			(effects
				(font
					(size 1.27 1.27)
				)
				(hide yes)
			)
		)
		(property "Datasheet" ""
			(at 46.99 107.95 0)
			(effects
				(font
					(size 1.27 1.27)
				)
				(hide yes)
			)
		)
		(property "Description" ""
			(at 46.99 107.95 0)
			(effects
				(font
					(size 1.27 1.27)
				)
				(hide yes)
			)
		)
		(property "Author" "Antmicro"
			(at 55.88 115.57 0)
			(effects
				(font
					(size 1.27 1.27)
					(thickness 0.15)
				)
				(justify left bottom)
				(hide yes)
			)
		)
		(property "License" "Apache-2.0"
			(at 55.88 118.11 0)
			(effects
				(font
					(size 1.27 1.27)
					(thickness 0.15)
				)
				(justify left bottom)
				(hide yes)
			)
		)
		(pin "1"
		)
		(instances
			(project "thunderbolt-gpu-adapter"
				(path ""
					(reference "#PWR0130")
					(unit 1)
				)
			)
		)
	)
	(symbol
		(lib_id "antmicroResistors0402:R_4k75_0.5%_0402")
		(at 41.91 303.53 90)
		(unit 1)
		(exclude_from_sim no)
		(in_bom yes)
		(on_board yes)
		(dnp no)
		(fields_autoplaced yes)
		(property "Reference" "R69"
			(at 40.005 299.72 90)
			(effects
				(font
					(size 1.27 1.27)
					(thickness 0.15)
				)
				(justify left)
			)
		)
		(property "Value" "R_4k75_0.5%_0402"
			(at 54.61 283.21 0)
			(effects
				(font
					(size 1.27 1.27)
					(thickness 0.15)
				)
				(justify left bottom)
				(hide yes)
			)
		)
		(property "Footprint" "antmicro-footprints:R_0402_1005Metric"
			(at 57.15 283.21 0)
			(effects
				(font
					(size 1.27 1.27)
					(thickness 0.15)
				)
				(justify left bottom)
				(hide yes)
			)
		)
		(property "Datasheet" "https://industrial.panasonic.com/cdbs/www-data/pdf/RDQ0000/ast-ind-151033.pdf"
			(at 59.69 283.21 0)
			(effects
				(font
					(size 1.27 1.27)
					(thickness 0.15)
				)
				(justify left bottom)
				(hide yes)
			)
		)
		(property "Description" ""
			(at 41.91 303.53 0)
			(effects
				(font
					(size 1.27 1.27)
				)
				(hide yes)
			)
		)
		(property "MPN" "ERJ-H2RD4751X"
			(at 62.23 283.21 0)
			(effects
				(font
					(size 1.27 1.27)
					(thickness 0.15)
				)
				(justify left bottom)
				(hide yes)
			)
		)
		(property "Manufacturer" "Panasonic"
			(at 64.77 283.21 0)
			(effects
				(font
					(size 1.27 1.27)
					(thickness 0.15)
				)
				(justify left bottom)
				(hide yes)
			)
		)
		(property "License" "Apache-2.0"
			(at 67.31 283.21 0)
			(effects
				(font
					(size 1.27 1.27)
					(thickness 0.15)
				)
				(justify left bottom)
				(hide yes)
			)
		)
		(property "Val" "4k75"
			(at 40.005 302.26 90)
			(effects
				(font
					(size 1.27 1.27)
					(thickness 0.15)
				)
				(justify left)
			)
		)
		(property "Tolerance" "0.5%"
			(at 39.37 303.53 90)
			(effects
				(font
					(size 1.27 1.27)
				)
				(justify left)
				(hide yes)
			)
		)
		(property "Author" "Antmicro"
			(at 69.85 283.21 0)
			(effects
				(font
					(size 1.27 1.27)
					(thickness 0.15)
				)
				(justify left bottom)
				(hide yes)
			)
		)
		(pin "1"
		)
		(pin "2"
		)
		(instances
			(project "thunderbolt-gpu-adapter"
				(path ""
					(reference "R69")
					(unit 1)
				)
			)
		)
	)
	(symbol
		(lib_id "antmicroResistors0402:R_10k_0402")
		(at 182.88 207.01 0)
		(unit 1)
		(exclude_from_sim no)
		(in_bom yes)
		(on_board yes)
		(dnp no)
		(property "Reference" "R79"
			(at 181.61 205.74 0)
			(effects
				(font
					(size 1.27 1.27)
					(thickness 0.15)
				)
			)
		)
		(property "Value" "R_10k_0402"
			(at 203.2 219.71 0)
			(effects
				(font
					(size 1.27 1.27)
					(thickness 0.15)
				)
				(justify left bottom)
				(hide yes)
			)
		)
		(property "Footprint" "antmicro-footprints:R_0402_1005Metric"
			(at 203.2 222.25 0)
			(effects
				(font
					(size 1.27 1.27)
					(thickness 0.15)
				)
				(justify left bottom)
				(hide yes)
			)
		)
		(property "Datasheet" "https://www.bourns.com/docs/product-datasheets/cr.pdf"
			(at 203.2 224.79 0)
			(effects
				(font
					(size 1.27 1.27)
					(thickness 0.15)
				)
				(justify left bottom)
				(hide yes)
			)
		)
		(property "Description" ""
			(at 182.88 207.01 0)
			(effects
				(font
					(size 1.27 1.27)
				)
				(hide yes)
			)
		)
		(property "MPN" "CR0402-FX-1002GLF"
			(at 203.2 227.33 0)
			(effects
				(font
					(size 1.27 1.27)
					(thickness 0.15)
				)
				(justify left bottom)
				(hide yes)
			)
		)
		(property "Manufacturer" "Bourns"
			(at 203.2 229.87 0)
			(effects
				(font
					(size 1.27 1.27)
					(thickness 0.15)
				)
				(justify left bottom)
				(hide yes)
			)
		)
		(property "License" "Apache-2.0"
			(at 203.2 232.41 0)
			(effects
				(font
					(size 1.27 1.27)
					(thickness 0.15)
				)
				(justify left bottom)
				(hide yes)
			)
		)
		(property "Val" "10k"
			(at 189.23 205.74 0)
			(effects
				(font
					(size 1.27 1.27)
					(thickness 0.15)
				)
			)
		)
		(property "Tolerance" "1%"
			(at 203.2 217.17 0)
			(effects
				(font
					(size 1.27 1.27)
				)
				(justify left bottom)
				(hide yes)
			)
		)
		(property "Author" "Antmicro"
			(at 203.2 234.95 0)
			(effects
				(font
					(size 1.27 1.27)
					(thickness 0.15)
				)
				(justify left bottom)
				(hide yes)
			)
		)
		(pin "1"
		)
		(pin "2"
		)
		(instances
			(project "thunderbolt-gpu-adapter"
				(path ""
					(reference "R79")
					(unit 1)
				)
			)
		)
	)
	(symbol
		(lib_id "antmicroResistors0402:R_10k_0402")
		(at 35.56 284.48 0)
		(unit 1)
		(exclude_from_sim no)
		(in_bom yes)
		(on_board yes)
		(dnp no)
		(property "Reference" "R65"
			(at 41.91 283.21 0)
			(effects
				(font
					(size 1.27 1.27)
					(thickness 0.15)
				)
			)
		)
		(property "Value" "R_10k_0402"
			(at 55.88 297.18 0)
			(effects
				(font
					(size 1.27 1.27)
					(thickness 0.15)
				)
				(justify left bottom)
				(hide yes)
			)
		)
		(property "Footprint" "antmicro-footprints:R_0402_1005Metric"
			(at 55.88 299.72 0)
			(effects
				(font
					(size 1.27 1.27)
					(thickness 0.15)
				)
				(justify left bottom)
				(hide yes)
			)
		)
		(property "Datasheet" "https://www.bourns.com/docs/product-datasheets/cr.pdf"
			(at 55.88 302.26 0)
			(effects
				(font
					(size 1.27 1.27)
					(thickness 0.15)
				)
				(justify left bottom)
				(hide yes)
			)
		)
		(property "Description" ""
			(at 35.56 284.48 0)
			(effects
				(font
					(size 1.27 1.27)
				)
				(hide yes)
			)
		)
		(property "MPN" "CR0402-FX-1002GLF"
			(at 55.88 304.8 0)
			(effects
				(font
					(size 1.27 1.27)
					(thickness 0.15)
				)
				(justify left bottom)
				(hide yes)
			)
		)
		(property "Manufacturer" "Bourns"
			(at 55.88 307.34 0)
			(effects
				(font
					(size 1.27 1.27)
					(thickness 0.15)
				)
				(justify left bottom)
				(hide yes)
			)
		)
		(property "License" "Apache-2.0"
			(at 55.88 309.88 0)
			(effects
				(font
					(size 1.27 1.27)
					(thickness 0.15)
				)
				(justify left bottom)
				(hide yes)
			)
		)
		(property "Val" "10k"
			(at 38.1 284.48 0)
			(effects
				(font
					(size 1.27 1.27)
					(thickness 0.15)
				)
			)
		)
		(property "Tolerance" "1%"
			(at 55.88 294.64 0)
			(effects
				(font
					(size 1.27 1.27)
				)
				(justify left bottom)
				(hide yes)
			)
		)
		(property "Author" "Antmicro"
			(at 55.88 312.42 0)
			(effects
				(font
					(size 1.27 1.27)
					(thickness 0.15)
				)
				(justify left bottom)
				(hide yes)
			)
		)
		(pin "1"
		)
		(pin "2"
		)
		(instances
			(project "thunderbolt-gpu-adapter"
				(path ""
					(reference "R65")
					(unit 1)
				)
			)
		)
	)
	(symbol
		(lib_id "antmicroResistors0402:R_10k_0402")
		(at 182.88 204.47 0)
		(unit 1)
		(exclude_from_sim no)
		(in_bom yes)
		(on_board yes)
		(dnp no)
		(property "Reference" "R78"
			(at 181.61 203.2 0)
			(effects
				(font
					(size 1.27 1.27)
					(thickness 0.15)
				)
			)
		)
		(property "Value" "R_10k_0402"
			(at 203.2 217.17 0)
			(effects
				(font
					(size 1.27 1.27)
					(thickness 0.15)
				)
				(justify left bottom)
				(hide yes)
			)
		)
		(property "Footprint" "antmicro-footprints:R_0402_1005Metric"
			(at 203.2 219.71 0)
			(effects
				(font
					(size 1.27 1.27)
					(thickness 0.15)
				)
				(justify left bottom)
				(hide yes)
			)
		)
		(property "Datasheet" "https://www.bourns.com/docs/product-datasheets/cr.pdf"
			(at 203.2 222.25 0)
			(effects
				(font
					(size 1.27 1.27)
					(thickness 0.15)
				)
				(justify left bottom)
				(hide yes)
			)
		)
		(property "Description" ""
			(at 182.88 204.47 0)
			(effects
				(font
					(size 1.27 1.27)
				)
				(hide yes)
			)
		)
		(property "MPN" "CR0402-FX-1002GLF"
			(at 203.2 224.79 0)
			(effects
				(font
					(size 1.27 1.27)
					(thickness 0.15)
				)
				(justify left bottom)
				(hide yes)
			)
		)
		(property "Manufacturer" "Bourns"
			(at 203.2 227.33 0)
			(effects
				(font
					(size 1.27 1.27)
					(thickness 0.15)
				)
				(justify left bottom)
				(hide yes)
			)
		)
		(property "License" "Apache-2.0"
			(at 203.2 229.87 0)
			(effects
				(font
					(size 1.27 1.27)
					(thickness 0.15)
				)
				(justify left bottom)
				(hide yes)
			)
		)
		(property "Val" "10k"
			(at 189.23 203.2 0)
			(effects
				(font
					(size 1.27 1.27)
					(thickness 0.15)
				)
			)
		)
		(property "Tolerance" "1%"
			(at 203.2 214.63 0)
			(effects
				(font
					(size 1.27 1.27)
				)
				(justify left bottom)
				(hide yes)
			)
		)
		(property "Author" "Antmicro"
			(at 203.2 232.41 0)
			(effects
				(font
					(size 1.27 1.27)
					(thickness 0.15)
				)
				(justify left bottom)
				(hide yes)
			)
		)
		(pin "1"
		)
		(pin "2"
		)
		(instances
			(project "thunderbolt-gpu-adapter"
				(path ""
					(reference "R78")
					(unit 1)
				)
			)
		)
	)
	(symbol
		(lib_id "antmicroResistors0402:R_3k3_0402")
		(at 113.03 365.76 90)
		(unit 1)
		(exclude_from_sim no)
		(in_bom yes)
		(on_board yes)
		(dnp no)
		(property "Reference" "R51"
			(at 114.3 361.95 90)
			(effects
				(font
					(size 1.27 1.27)
					(thickness 0.15)
				)
				(justify right)
			)
		)
		(property "Value" "R_3k3_0402"
			(at 125.73 345.44 0)
			(effects
				(font
					(size 1.27 1.27)
					(thickness 0.15)
				)
				(justify left bottom)
				(hide yes)
			)
		)
		(property "Footprint" "antmicro-footprints:R_0402_1005Metric"
			(at 128.27 345.44 0)
			(effects
				(font
					(size 1.27 1.27)
					(thickness 0.15)
				)
				(justify left bottom)
				(hide yes)
			)
		)
		(property "Datasheet" "https://www.bourns.com/docs/product-datasheets/cr.pdf"
			(at 130.81 345.44 0)
			(effects
				(font
					(size 1.27 1.27)
					(thickness 0.15)
				)
				(justify left bottom)
				(hide yes)
			)
		)
		(property "Description" ""
			(at 113.03 365.76 0)
			(effects
				(font
					(size 1.27 1.27)
				)
				(hide yes)
			)
		)
		(property "MPN" "CR0402-FX-3301GLF"
			(at 133.35 345.44 0)
			(effects
				(font
					(size 1.27 1.27)
					(thickness 0.15)
				)
				(justify left bottom)
				(hide yes)
			)
		)
		(property "Manufacturer" "Bourns"
			(at 135.89 345.44 0)
			(effects
				(font
					(size 1.27 1.27)
					(thickness 0.15)
				)
				(justify left bottom)
				(hide yes)
			)
		)
		(property "License" "Apache-2.0"
			(at 138.43 345.44 0)
			(effects
				(font
					(size 1.27 1.27)
					(thickness 0.15)
				)
				(justify left bottom)
				(hide yes)
			)
		)
		(property "Val" "3k3"
			(at 114.3 364.49 90)
			(effects
				(font
					(size 1.27 1.27)
					(thickness 0.15)
				)
				(justify right)
			)
		)
		(property "Tolerance" "1%"
			(at 123.19 345.44 0)
			(effects
				(font
					(size 1.27 1.27)
				)
				(justify left bottom)
				(hide yes)
			)
		)
		(property "Author" "Antmicro"
			(at 140.97 345.44 0)
			(effects
				(font
					(size 1.27 1.27)
					(thickness 0.15)
				)
				(justify left bottom)
				(hide yes)
			)
		)
		(pin "1"
		)
		(pin "2"
		)
		(instances
			(project "thunderbolt-gpu-adapter"
				(path ""
					(reference "R51")
					(unit 1)
				)
			)
		)
	)
	(symbol
		(lib_id "antmicropower:GND")
		(at 215.9 355.6 0)
		(unit 1)
		(exclude_from_sim no)
		(in_bom yes)
		(on_board yes)
		(dnp no)
		(property "Reference" "#PWR0147"
			(at 215.9 361.95 0)
			(effects
				(font
					(size 1.27 1.27)
				)
				(hide yes)
			)
		)
		(property "Value" "GND"
			(at 215.9 359.41 0)
			(effects
				(font
					(size 1.27 1.27)
				)
			)
		)
		(property "Footprint" ""
			(at 215.9 355.6 0)
			(effects
				(font
					(size 1.27 1.27)
				)
				(hide yes)
			)
		)
		(property "Datasheet" ""
			(at 215.9 355.6 0)
			(effects
				(font
					(size 1.27 1.27)
				)
				(hide yes)
			)
		)
		(property "Description" ""
			(at 215.9 355.6 0)
			(effects
				(font
					(size 1.27 1.27)
				)
				(hide yes)
			)
		)
		(property "Author" "Antmicro"
			(at 224.79 363.22 0)
			(effects
				(font
					(size 1.27 1.27)
					(thickness 0.15)
				)
				(justify left bottom)
				(hide yes)
			)
		)
		(property "License" "Apache-2.0"
			(at 224.79 365.76 0)
			(effects
				(font
					(size 1.27 1.27)
					(thickness 0.15)
				)
				(justify left bottom)
				(hide yes)
			)
		)
		(pin "1"
		)
		(instances
			(project "thunderbolt-gpu-adapter"
				(path ""
					(reference "#PWR0147")
					(unit 1)
				)
			)
		)
	)
	(symbol
		(lib_id "antmicropower:GND")
		(at 184.15 311.15 0)
		(unit 1)
		(exclude_from_sim no)
		(in_bom yes)
		(on_board yes)
		(dnp no)
		(property "Reference" "#PWR0135"
			(at 184.15 317.5 0)
			(effects
				(font
					(size 1.27 1.27)
				)
				(hide yes)
			)
		)
		(property "Value" "GND"
			(at 184.15 314.96 0)
			(effects
				(font
					(size 1.27 1.27)
				)
			)
		)
		(property "Footprint" ""
			(at 184.15 311.15 0)
			(effects
				(font
					(size 1.27 1.27)
				)
				(hide yes)
			)
		)
		(property "Datasheet" ""
			(at 184.15 311.15 0)
			(effects
				(font
					(size 1.27 1.27)
				)
				(hide yes)
			)
		)
		(property "Description" ""
			(at 184.15 311.15 0)
			(effects
				(font
					(size 1.27 1.27)
				)
				(hide yes)
			)
		)
		(property "Author" "Antmicro"
			(at 193.04 318.77 0)
			(effects
				(font
					(size 1.27 1.27)
					(thickness 0.15)
				)
				(justify left bottom)
				(hide yes)
			)
		)
		(property "License" "Apache-2.0"
			(at 193.04 321.31 0)
			(effects
				(font
					(size 1.27 1.27)
					(thickness 0.15)
				)
				(justify left bottom)
				(hide yes)
			)
		)
		(pin "1"
		)
		(instances
			(project "thunderbolt-gpu-adapter"
				(path ""
					(reference "#PWR0135")
					(unit 1)
				)
			)
		)
	)
	(symbol
		(lib_id "antmicropower:GND")
		(at 115.57 285.75 0)
		(unit 1)
		(exclude_from_sim no)
		(in_bom yes)
		(on_board yes)
		(dnp no)
		(property "Reference" "#PWR0144"
			(at 115.57 292.1 0)
			(effects
				(font
					(size 1.27 1.27)
				)
				(hide yes)
			)
		)
		(property "Value" "GND"
			(at 115.57 289.56 0)
			(effects
				(font
					(size 1.27 1.27)
				)
			)
		)
		(property "Footprint" ""
			(at 115.57 285.75 0)
			(effects
				(font
					(size 1.27 1.27)
				)
				(hide yes)
			)
		)
		(property "Datasheet" ""
			(at 115.57 285.75 0)
			(effects
				(font
					(size 1.27 1.27)
				)
				(hide yes)
			)
		)
		(property "Description" ""
			(at 115.57 285.75 0)
			(effects
				(font
					(size 1.27 1.27)
				)
				(hide yes)
			)
		)
		(property "Author" "Antmicro"
			(at 124.46 293.37 0)
			(effects
				(font
					(size 1.27 1.27)
					(thickness 0.15)
				)
				(justify left bottom)
				(hide yes)
			)
		)
		(property "License" "Apache-2.0"
			(at 124.46 295.91 0)
			(effects
				(font
					(size 1.27 1.27)
					(thickness 0.15)
				)
				(justify left bottom)
				(hide yes)
			)
		)
		(pin "1"
		)
		(instances
			(project "thunderbolt-gpu-adapter"
				(path ""
					(reference "#PWR0144")
					(unit 1)
				)
			)
		)
	)
	(symbol
		(lib_id "antmicroResonators:Resonator_25MHz_ABM8G")
		(at 198.12 358.14 270)
		(unit 1)
		(exclude_from_sim no)
		(in_bom yes)
		(on_board yes)
		(dnp no)
		(fields_autoplaced yes)
		(property "Reference" "Y1"
			(at 201.93 360.68 90)
			(effects
				(font
					(size 1.27 1.27)
					(thickness 0.15)
				)
				(justify left)
			)
		)
		(property "Value" "Resonator_25MHz_ABM8G"
			(at 185.42 373.38 0)
			(effects
				(font
					(size 1.27 1.27)
					(thickness 0.15)
				)
				(justify left bottom)
				(hide yes)
			)
		)
		(property "Footprint" "antmicro-footprints:Resonator_SMD_Abracon_ABM8G_3.2x2.5mm"
			(at 182.88 373.38 0)
			(effects
				(font
					(size 1.27 1.27)
					(thickness 0.15)
				)
				(justify left bottom)
				(hide yes)
			)
		)
		(property "Datasheet" "https://abracon.com/Resonators/ABM8G.pdf"
			(at 180.34 373.38 0)
			(effects
				(font
					(size 1.27 1.27)
					(thickness 0.15)
				)
				(justify left bottom)
				(hide yes)
			)
		)
		(property "Description" ""
			(at 198.12 358.14 0)
			(effects
				(font
					(size 1.27 1.27)
				)
				(hide yes)
			)
		)
		(property "MPN" "ABM8G-25.000MHZ-18-D2Y-T3"
			(at 201.93 361.95 90)
			(effects
				(font
					(size 1.27 1.27)
					(thickness 0.15)
				)
				(justify left)
				(hide yes)
			)
		)
		(property "Manufacturer" "Abracon"
			(at 177.8 373.38 0)
			(effects
				(font
					(size 1.27 1.27)
					(thickness 0.15)
				)
				(justify left bottom)
				(hide yes)
			)
		)
		(property "License" "Apache-2.0"
			(at 172.72 373.38 0)
			(effects
				(font
					(size 1.27 1.27)
					(thickness 0.15)
				)
				(justify left bottom)
				(hide yes)
			)
		)
		(property "Author" "Antmicro"
			(at 175.26 373.38 0)
			(effects
				(font
					(size 1.27 1.27)
					(thickness 0.15)
				)
				(justify left bottom)
				(hide yes)
			)
		)
		(property "Val" "25 MHz"
			(at 201.93 363.22 90)
			(effects
				(font
					(size 1.27 1.27)
					(thickness 0.15)
				)
				(justify left)
			)
		)
		(pin "1"
		)
		(pin "2"
		)
		(pin "3"
		)
		(pin "4"
		)
		(instances
			(project "thunderbolt-gpu-adapter"
				(path ""
					(reference "Y1")
					(unit 1)
				)
			)
		)
	)
	(symbol
		(lib_id "antmicropower:GND")
		(at 137.16 105.41 0)
		(unit 1)
		(exclude_from_sim no)
		(in_bom yes)
		(on_board yes)
		(dnp no)
		(property "Reference" "#PWR0139"
			(at 137.16 111.76 0)
			(effects
				(font
					(size 1.27 1.27)
				)
				(hide yes)
			)
		)
		(property "Value" "GND"
			(at 137.16 109.22 0)
			(effects
				(font
					(size 1.27 1.27)
				)
			)
		)
		(property "Footprint" ""
			(at 137.16 105.41 0)
			(effects
				(font
					(size 1.27 1.27)
				)
				(hide yes)
			)
		)
		(property "Datasheet" ""
			(at 137.16 105.41 0)
			(effects
				(font
					(size 1.27 1.27)
				)
				(hide yes)
			)
		)
		(property "Description" ""
			(at 137.16 105.41 0)
			(effects
				(font
					(size 1.27 1.27)
				)
				(hide yes)
			)
		)
		(property "Author" "Antmicro"
			(at 146.05 113.03 0)
			(effects
				(font
					(size 1.27 1.27)
					(thickness 0.15)
				)
				(justify left bottom)
				(hide yes)
			)
		)
		(property "License" "Apache-2.0"
			(at 146.05 115.57 0)
			(effects
				(font
					(size 1.27 1.27)
					(thickness 0.15)
				)
				(justify left bottom)
				(hide yes)
			)
		)
		(pin "1"
		)
		(instances
			(project "thunderbolt-gpu-adapter"
				(path ""
					(reference "#PWR0139")
					(unit 1)
				)
			)
		)
	)
	(symbol
		(lib_id "antmicroResistors0402:R_10k_0402")
		(at 182.88 209.55 0)
		(unit 1)
		(exclude_from_sim no)
		(in_bom yes)
		(on_board yes)
		(dnp no)
		(property "Reference" "R80"
			(at 181.61 208.28 0)
			(effects
				(font
					(size 1.27 1.27)
					(thickness 0.15)
				)
			)
		)
		(property "Value" "R_10k_0402"
			(at 203.2 222.25 0)
			(effects
				(font
					(size 1.27 1.27)
					(thickness 0.15)
				)
				(justify left bottom)
				(hide yes)
			)
		)
		(property "Footprint" "antmicro-footprints:R_0402_1005Metric"
			(at 203.2 224.79 0)
			(effects
				(font
					(size 1.27 1.27)
					(thickness 0.15)
				)
				(justify left bottom)
				(hide yes)
			)
		)
		(property "Datasheet" "https://www.bourns.com/docs/product-datasheets/cr.pdf"
			(at 203.2 227.33 0)
			(effects
				(font
					(size 1.27 1.27)
					(thickness 0.15)
				)
				(justify left bottom)
				(hide yes)
			)
		)
		(property "Description" ""
			(at 182.88 209.55 0)
			(effects
				(font
					(size 1.27 1.27)
				)
				(hide yes)
			)
		)
		(property "MPN" "CR0402-FX-1002GLF"
			(at 203.2 229.87 0)
			(effects
				(font
					(size 1.27 1.27)
					(thickness 0.15)
				)
				(justify left bottom)
				(hide yes)
			)
		)
		(property "Manufacturer" "Bourns"
			(at 203.2 232.41 0)
			(effects
				(font
					(size 1.27 1.27)
					(thickness 0.15)
				)
				(justify left bottom)
				(hide yes)
			)
		)
		(property "License" "Apache-2.0"
			(at 203.2 234.95 0)
			(effects
				(font
					(size 1.27 1.27)
					(thickness 0.15)
				)
				(justify left bottom)
				(hide yes)
			)
		)
		(property "Val" "10k"
			(at 189.23 208.28 0)
			(effects
				(font
					(size 1.27 1.27)
					(thickness 0.15)
				)
			)
		)
		(property "Tolerance" "1%"
			(at 203.2 219.71 0)
			(effects
				(font
					(size 1.27 1.27)
				)
				(justify left bottom)
				(hide yes)
			)
		)
		(property "Author" "Antmicro"
			(at 203.2 237.49 0)
			(effects
				(font
					(size 1.27 1.27)
					(thickness 0.15)
				)
				(justify left bottom)
				(hide yes)
			)
		)
		(pin "1"
		)
		(pin "2"
		)
		(instances
			(project "thunderbolt-gpu-adapter"
				(path ""
					(reference "R80")
					(unit 1)
				)
			)
		)
	)
	(symbol
		(lib_id "antmicroResistors0402:R_1M_0402")
		(at 50.8 105.41 90)
		(unit 1)
		(exclude_from_sim no)
		(in_bom yes)
		(on_board yes)
		(dnp no)
		(fields_autoplaced yes)
		(property "Reference" "R55"
			(at 52.705 101.6 90)
			(effects
				(font
					(size 1.27 1.27)
					(thickness 0.15)
				)
				(justify right)
			)
		)
		(property "Value" "R_1M_0402"
			(at 63.5 85.09 0)
			(effects
				(font
					(size 1.27 1.27)
					(thickness 0.15)
				)
				(justify left bottom)
				(hide yes)
			)
		)
		(property "Footprint" "antmicro-footprints:R_0402_1005Metric"
			(at 66.04 85.09 0)
			(effects
				(font
					(size 1.27 1.27)
					(thickness 0.15)
				)
				(justify left bottom)
				(hide yes)
			)
		)
		(property "Datasheet" "https://www.bourns.com/docs/product-datasheets/cr.pdf"
			(at 68.58 85.09 0)
			(effects
				(font
					(size 1.27 1.27)
					(thickness 0.15)
				)
				(justify left bottom)
				(hide yes)
			)
		)
		(property "Description" ""
			(at 50.8 105.41 0)
			(effects
				(font
					(size 1.27 1.27)
				)
				(hide yes)
			)
		)
		(property "MPN" "CR0402-FX-1004GLF"
			(at 71.12 85.09 0)
			(effects
				(font
					(size 1.27 1.27)
					(thickness 0.15)
				)
				(justify left bottom)
				(hide yes)
			)
		)
		(property "Manufacturer" "Bourns"
			(at 73.66 85.09 0)
			(effects
				(font
					(size 1.27 1.27)
					(thickness 0.15)
				)
				(justify left bottom)
				(hide yes)
			)
		)
		(property "License" "Apache-2.0"
			(at 76.2 85.09 0)
			(effects
				(font
					(size 1.27 1.27)
					(thickness 0.15)
				)
				(justify left bottom)
				(hide yes)
			)
		)
		(property "Val" "1M"
			(at 52.705 104.14 90)
			(effects
				(font
					(size 1.27 1.27)
					(thickness 0.15)
				)
				(justify right)
			)
		)
		(property "Tolerance" "1%"
			(at 60.96 85.09 0)
			(effects
				(font
					(size 1.27 1.27)
				)
				(justify left bottom)
				(hide yes)
			)
		)
		(property "Author" "Antmicro"
			(at 78.74 85.09 0)
			(effects
				(font
					(size 1.27 1.27)
					(thickness 0.15)
				)
				(justify left bottom)
				(hide yes)
			)
		)
		(pin "1"
		)
		(pin "2"
		)
		(instances
			(project "thunderbolt-gpu-adapter"
				(path ""
					(reference "R55")
					(unit 1)
				)
			)
		)
	)
	(symbol
		(lib_id "antmicroCapacitors0402:C_220n_0402")
		(at 44.45 73.66 0)
		(unit 1)
		(exclude_from_sim no)
		(in_bom yes)
		(on_board yes)
		(dnp no)
		(property "Reference" "C103"
			(at 50.165 72.39 0)
			(effects
				(font
					(size 1.27 1.27)
					(thickness 0.15)
				)
			)
		)
		(property "Value" "C_220n_0402"
			(at 64.77 83.82 0)
			(effects
				(font
					(size 1.27 1.27)
					(thickness 0.15)
				)
				(justify left bottom)
				(hide yes)
			)
		)
		(property "Footprint" "antmicro-footprints:C_0402_1005Metric"
			(at 64.77 86.36 0)
			(effects
				(font
					(size 1.27 1.27)
					(thickness 0.15)
				)
				(justify left bottom)
				(hide yes)
			)
		)
		(property "Datasheet" "https://www.yageo.com/en/Chart/Download/pdf/CC0402KRX5R6BB224"
			(at 64.77 88.9 0)
			(effects
				(font
					(size 1.27 1.27)
					(thickness 0.15)
				)
				(justify left bottom)
				(hide yes)
			)
		)
		(property "Description" ""
			(at 44.45 73.66 0)
			(effects
				(font
					(size 1.27 1.27)
				)
				(hide yes)
			)
		)
		(property "MPN" "CC0402KRX5R6BB224"
			(at 64.77 91.44 0)
			(effects
				(font
					(size 1.27 1.27)
					(thickness 0.15)
				)
				(justify left bottom)
				(hide yes)
			)
		)
		(property "Manufacturer" "YAGEO"
			(at 64.77 93.98 0)
			(effects
				(font
					(size 1.27 1.27)
					(thickness 0.15)
				)
				(justify left bottom)
				(hide yes)
			)
		)
		(property "License" "Apache-2.0"
			(at 64.77 96.52 0)
			(effects
				(font
					(size 1.27 1.27)
					(thickness 0.15)
				)
				(justify left bottom)
				(hide yes)
			)
		)
		(property "Val" "220n"
			(at 50.165 74.93 0)
			(effects
				(font
					(size 1.27 1.27)
					(thickness 0.15)
				)
			)
		)
		(property "Voltage" ""
			(at 64.77 101.6 0)
			(effects
				(font
					(size 1.27 1.27)
				)
				(justify left bottom)
				(hide yes)
			)
		)
		(property "Dielectric" ""
			(at 64.77 104.14 0)
			(effects
				(font
					(size 1.27 1.27)
				)
				(justify left bottom)
				(hide yes)
			)
		)
		(property "Author" "Antmicro"
			(at 64.77 99.06 0)
			(effects
				(font
					(size 1.27 1.27)
					(thickness 0.15)
				)
				(justify left bottom)
				(hide yes)
			)
		)
		(pin "1"
		)
		(pin "2"
		)
		(instances
			(project "thunderbolt-gpu-adapter"
				(path ""
					(reference "C103")
					(unit 1)
				)
			)
		)
	)
	(symbol
		(lib_id "antmicroResistors0402:R_1M_0402")
		(at 129.54 93.98 0)
		(unit 1)
		(exclude_from_sim no)
		(in_bom yes)
		(on_board yes)
		(dnp no)
		(property "Reference" "R70"
			(at 132.08 92.075 0)
			(effects
				(font
					(size 1.27 1.27)
					(thickness 0.15)
				)
			)
		)
		(property "Value" "R_1M_0402"
			(at 149.86 106.68 0)
			(effects
				(font
					(size 1.27 1.27)
					(thickness 0.15)
				)
				(justify left bottom)
				(hide yes)
			)
		)
		(property "Footprint" "antmicro-footprints:R_0402_1005Metric"
			(at 149.86 109.22 0)
			(effects
				(font
					(size 1.27 1.27)
					(thickness 0.15)
				)
				(justify left bottom)
				(hide yes)
			)
		)
		(property "Datasheet" "https://www.bourns.com/docs/product-datasheets/cr.pdf"
			(at 149.86 111.76 0)
			(effects
				(font
					(size 1.27 1.27)
					(thickness 0.15)
				)
				(justify left bottom)
				(hide yes)
			)
		)
		(property "Description" ""
			(at 129.54 93.98 0)
			(effects
				(font
					(size 1.27 1.27)
				)
				(hide yes)
			)
		)
		(property "MPN" "CR0402-FX-1004GLF"
			(at 149.86 114.3 0)
			(effects
				(font
					(size 1.27 1.27)
					(thickness 0.15)
				)
				(justify left bottom)
				(hide yes)
			)
		)
		(property "Manufacturer" "Bourns"
			(at 149.86 116.84 0)
			(effects
				(font
					(size 1.27 1.27)
					(thickness 0.15)
				)
				(justify left bottom)
				(hide yes)
			)
		)
		(property "License" "Apache-2.0"
			(at 149.86 119.38 0)
			(effects
				(font
					(size 1.27 1.27)
					(thickness 0.15)
				)
				(justify left bottom)
				(hide yes)
			)
		)
		(property "Val" "1M"
			(at 132.08 93.98 0)
			(effects
				(font
					(size 1.27 1.27)
					(thickness 0.15)
				)
			)
		)
		(property "Tolerance" "1%"
			(at 149.86 104.14 0)
			(effects
				(font
					(size 1.27 1.27)
				)
				(justify left bottom)
				(hide yes)
			)
		)
		(property "Author" "Antmicro"
			(at 149.86 121.92 0)
			(effects
				(font
					(size 1.27 1.27)
					(thickness 0.15)
				)
				(justify left bottom)
				(hide yes)
			)
		)
		(pin "1"
		)
		(pin "2"
		)
		(instances
			(project "thunderbolt-gpu-adapter"
				(path ""
					(reference "R70")
					(unit 1)
				)
			)
		)
	)
	(symbol
		(lib_id "antmicroResistors0402:R_100k_0402")
		(at 114.3 181.61 0)
		(unit 1)
		(exclude_from_sim no)
		(in_bom yes)
		(on_board yes)
		(dnp no)
		(fields_autoplaced yes)
		(property "Reference" "R57"
			(at 116.84 175.26 0)
			(effects
				(font
					(size 1.27 1.27)
					(thickness 0.15)
				)
			)
		)
		(property "Value" "R_100k_0402"
			(at 134.62 194.31 0)
			(effects
				(font
					(size 1.27 1.27)
					(thickness 0.15)
				)
				(justify left bottom)
				(hide yes)
			)
		)
		(property "Footprint" "antmicro-footprints:R_0402_1005Metric"
			(at 134.62 196.85 0)
			(effects
				(font
					(size 1.27 1.27)
					(thickness 0.15)
				)
				(justify left bottom)
				(hide yes)
			)
		)
		(property "Datasheet" "https://www.bourns.com/docs/product-datasheets/cr.pdf"
			(at 134.62 199.39 0)
			(effects
				(font
					(size 1.27 1.27)
					(thickness 0.15)
				)
				(justify left bottom)
				(hide yes)
			)
		)
		(property "Description" ""
			(at 114.3 181.61 0)
			(effects
				(font
					(size 1.27 1.27)
				)
				(hide yes)
			)
		)
		(property "MPN" "CR0402-FX-1003GLF"
			(at 134.62 201.93 0)
			(effects
				(font
					(size 1.27 1.27)
					(thickness 0.15)
				)
				(justify left bottom)
				(hide yes)
			)
		)
		(property "Manufacturer" "Bourns"
			(at 134.62 204.47 0)
			(effects
				(font
					(size 1.27 1.27)
					(thickness 0.15)
				)
				(justify left bottom)
				(hide yes)
			)
		)
		(property "License" "Apache-2.0"
			(at 134.62 207.01 0)
			(effects
				(font
					(size 1.27 1.27)
					(thickness 0.15)
				)
				(justify left bottom)
				(hide yes)
			)
		)
		(property "Val" "100k"
			(at 116.84 177.8 0)
			(effects
				(font
					(size 1.27 1.27)
					(thickness 0.15)
				)
			)
		)
		(property "Tolerance" "1%"
			(at 134.62 191.77 0)
			(effects
				(font
					(size 1.27 1.27)
				)
				(justify left bottom)
				(hide yes)
			)
		)
		(property "Author" "Antmicro"
			(at 134.62 209.55 0)
			(effects
				(font
					(size 1.27 1.27)
					(thickness 0.15)
				)
				(justify left bottom)
				(hide yes)
			)
		)
		(pin "1"
		)
		(pin "2"
		)
		(instances
			(project "thunderbolt-gpu-adapter"
				(path ""
					(reference "R57")
					(unit 1)
				)
			)
		)
	)
	(symbol
		(lib_id "antmicroCapacitors0402:C_220n_0402")
		(at 39.37 71.12 0)
		(unit 1)
		(exclude_from_sim no)
		(in_bom yes)
		(on_board yes)
		(dnp no)
		(property "Reference" "C100"
			(at 38.735 69.85 0)
			(effects
				(font
					(size 1.27 1.27)
					(thickness 0.15)
				)
			)
		)
		(property "Value" "C_220n_0402"
			(at 59.69 81.28 0)
			(effects
				(font
					(size 1.27 1.27)
					(thickness 0.15)
				)
				(justify left bottom)
				(hide yes)
			)
		)
		(property "Footprint" "antmicro-footprints:C_0402_1005Metric"
			(at 59.69 83.82 0)
			(effects
				(font
					(size 1.27 1.27)
					(thickness 0.15)
				)
				(justify left bottom)
				(hide yes)
			)
		)
		(property "Datasheet" "https://www.yageo.com/en/Chart/Download/pdf/CC0402KRX5R6BB224"
			(at 59.69 86.36 0)
			(effects
				(font
					(size 1.27 1.27)
					(thickness 0.15)
				)
				(justify left bottom)
				(hide yes)
			)
		)
		(property "Description" ""
			(at 39.37 71.12 0)
			(effects
				(font
					(size 1.27 1.27)
				)
				(hide yes)
			)
		)
		(property "MPN" "CC0402KRX5R6BB224"
			(at 59.69 88.9 0)
			(effects
				(font
					(size 1.27 1.27)
					(thickness 0.15)
				)
				(justify left bottom)
				(hide yes)
			)
		)
		(property "Manufacturer" "YAGEO"
			(at 59.69 91.44 0)
			(effects
				(font
					(size 1.27 1.27)
					(thickness 0.15)
				)
				(justify left bottom)
				(hide yes)
			)
		)
		(property "License" "Apache-2.0"
			(at 59.69 93.98 0)
			(effects
				(font
					(size 1.27 1.27)
					(thickness 0.15)
				)
				(justify left bottom)
				(hide yes)
			)
		)
		(property "Val" "220n"
			(at 38.735 72.39 0)
			(effects
				(font
					(size 1.27 1.27)
					(thickness 0.15)
				)
			)
		)
		(property "Voltage" ""
			(at 59.69 99.06 0)
			(effects
				(font
					(size 1.27 1.27)
				)
				(justify left bottom)
				(hide yes)
			)
		)
		(property "Dielectric" ""
			(at 59.69 101.6 0)
			(effects
				(font
					(size 1.27 1.27)
				)
				(justify left bottom)
				(hide yes)
			)
		)
		(property "Author" "Antmicro"
			(at 59.69 96.52 0)
			(effects
				(font
					(size 1.27 1.27)
					(thickness 0.15)
				)
				(justify left bottom)
				(hide yes)
			)
		)
		(pin "1"
		)
		(pin "2"
		)
		(instances
			(project "thunderbolt-gpu-adapter"
				(path ""
					(reference "C100")
					(unit 1)
				)
			)
		)
	)
	(symbol
		(lib_id "antmicroResistors0402:R_10k_0402")
		(at 35.56 289.56 0)
		(unit 1)
		(exclude_from_sim no)
		(in_bom yes)
		(on_board yes)
		(dnp no)
		(property "Reference" "R67"
			(at 41.91 288.29 0)
			(effects
				(font
					(size 1.27 1.27)
					(thickness 0.15)
				)
			)
		)
		(property "Value" "R_10k_0402"
			(at 55.88 302.26 0)
			(effects
				(font
					(size 1.27 1.27)
					(thickness 0.15)
				)
				(justify left bottom)
				(hide yes)
			)
		)
		(property "Footprint" "antmicro-footprints:R_0402_1005Metric"
			(at 55.88 304.8 0)
			(effects
				(font
					(size 1.27 1.27)
					(thickness 0.15)
				)
				(justify left bottom)
				(hide yes)
			)
		)
		(property "Datasheet" "https://www.bourns.com/docs/product-datasheets/cr.pdf"
			(at 55.88 307.34 0)
			(effects
				(font
					(size 1.27 1.27)
					(thickness 0.15)
				)
				(justify left bottom)
				(hide yes)
			)
		)
		(property "Description" ""
			(at 35.56 289.56 0)
			(effects
				(font
					(size 1.27 1.27)
				)
				(hide yes)
			)
		)
		(property "MPN" "CR0402-FX-1002GLF"
			(at 55.88 309.88 0)
			(effects
				(font
					(size 1.27 1.27)
					(thickness 0.15)
				)
				(justify left bottom)
				(hide yes)
			)
		)
		(property "Manufacturer" "Bourns"
			(at 55.88 312.42 0)
			(effects
				(font
					(size 1.27 1.27)
					(thickness 0.15)
				)
				(justify left bottom)
				(hide yes)
			)
		)
		(property "License" "Apache-2.0"
			(at 55.88 314.96 0)
			(effects
				(font
					(size 1.27 1.27)
					(thickness 0.15)
				)
				(justify left bottom)
				(hide yes)
			)
		)
		(property "Val" "10k"
			(at 38.1 289.56 0)
			(effects
				(font
					(size 1.27 1.27)
					(thickness 0.15)
				)
			)
		)
		(property "Tolerance" "1%"
			(at 55.88 299.72 0)
			(effects
				(font
					(size 1.27 1.27)
				)
				(justify left bottom)
				(hide yes)
			)
		)
		(property "Author" "Antmicro"
			(at 55.88 317.5 0)
			(effects
				(font
					(size 1.27 1.27)
					(thickness 0.15)
				)
				(justify left bottom)
				(hide yes)
			)
		)
		(pin "1"
		)
		(pin "2"
		)
		(instances
			(project "thunderbolt-gpu-adapter"
				(path ""
					(reference "R67")
					(unit 1)
				)
			)
		)
	)
	(symbol
		(lib_id "antmicroResistors0402:R_100k_0402")
		(at 182.88 212.09 0)
		(unit 1)
		(exclude_from_sim no)
		(in_bom yes)
		(on_board yes)
		(dnp no)
		(property "Reference" "R81"
			(at 181.61 210.82 0)
			(effects
				(font
					(size 1.27 1.27)
					(thickness 0.15)
				)
			)
		)
		(property "Value" "R_100k_0402"
			(at 203.2 224.79 0)
			(effects
				(font
					(size 1.27 1.27)
					(thickness 0.15)
				)
				(justify left bottom)
				(hide yes)
			)
		)
		(property "Footprint" "antmicro-footprints:R_0402_1005Metric"
			(at 203.2 227.33 0)
			(effects
				(font
					(size 1.27 1.27)
					(thickness 0.15)
				)
				(justify left bottom)
				(hide yes)
			)
		)
		(property "Datasheet" "https://www.bourns.com/docs/product-datasheets/cr.pdf"
			(at 203.2 229.87 0)
			(effects
				(font
					(size 1.27 1.27)
					(thickness 0.15)
				)
				(justify left bottom)
				(hide yes)
			)
		)
		(property "Description" ""
			(at 182.88 212.09 0)
			(effects
				(font
					(size 1.27 1.27)
				)
				(hide yes)
			)
		)
		(property "MPN" "CR0402-FX-1003GLF"
			(at 203.2 232.41 0)
			(effects
				(font
					(size 1.27 1.27)
					(thickness 0.15)
				)
				(justify left bottom)
				(hide yes)
			)
		)
		(property "Manufacturer" "Bourns"
			(at 203.2 234.95 0)
			(effects
				(font
					(size 1.27 1.27)
					(thickness 0.15)
				)
				(justify left bottom)
				(hide yes)
			)
		)
		(property "License" "Apache-2.0"
			(at 203.2 237.49 0)
			(effects
				(font
					(size 1.27 1.27)
					(thickness 0.15)
				)
				(justify left bottom)
				(hide yes)
			)
		)
		(property "Val" "100k"
			(at 189.865 210.82 0)
			(effects
				(font
					(size 1.27 1.27)
					(thickness 0.15)
				)
			)
		)
		(property "Tolerance" "1%"
			(at 203.2 222.25 0)
			(effects
				(font
					(size 1.27 1.27)
				)
				(justify left bottom)
				(hide yes)
			)
		)
		(property "Author" "Antmicro"
			(at 203.2 240.03 0)
			(effects
				(font
					(size 1.27 1.27)
					(thickness 0.15)
				)
				(justify left bottom)
				(hide yes)
			)
		)
		(pin "1"
		)
		(pin "2"
		)
		(instances
			(project "thunderbolt-gpu-adapter"
				(path ""
					(reference "R81")
					(unit 1)
				)
			)
		)
	)
	(symbol
		(lib_id "antmicropower:GND")
		(at 111.76 248.92 0)
		(mirror y)
		(unit 1)
		(exclude_from_sim no)
		(in_bom yes)
		(on_board yes)
		(dnp no)
		(property "Reference" "#PWR0133"
			(at 111.76 255.27 0)
			(effects
				(font
					(size 1.27 1.27)
				)
				(hide yes)
			)
		)
		(property "Value" "GND"
			(at 111.76 252.73 0)
			(effects
				(font
					(size 1.27 1.27)
				)
			)
		)
		(property "Footprint" ""
			(at 111.76 248.92 0)
			(effects
				(font
					(size 1.27 1.27)
				)
				(hide yes)
			)
		)
		(property "Datasheet" ""
			(at 111.76 248.92 0)
			(effects
				(font
					(size 1.27 1.27)
				)
				(hide yes)
			)
		)
		(property "Description" ""
			(at 111.76 248.92 0)
			(effects
				(font
					(size 1.27 1.27)
				)
				(hide yes)
			)
		)
		(property "Author" "Antmicro"
			(at 102.87 256.54 0)
			(effects
				(font
					(size 1.27 1.27)
					(thickness 0.15)
				)
				(justify left bottom)
				(hide yes)
			)
		)
		(property "License" "Apache-2.0"
			(at 102.87 259.08 0)
			(effects
				(font
					(size 1.27 1.27)
					(thickness 0.15)
				)
				(justify left bottom)
				(hide yes)
			)
		)
		(pin "1"
		)
		(instances
			(project "thunderbolt-gpu-adapter"
				(path ""
					(reference "#PWR0133")
					(unit 1)
				)
			)
		)
	)
	(symbol
		(lib_id "antmicropower:GND")
		(at 50.8 107.95 0)
		(unit 1)
		(exclude_from_sim no)
		(in_bom yes)
		(on_board yes)
		(dnp no)
		(property "Reference" "#PWR0131"
			(at 50.8 114.3 0)
			(effects
				(font
					(size 1.27 1.27)
				)
				(hide yes)
			)
		)
		(property "Value" "GND"
			(at 50.8 111.76 0)
			(effects
				(font
					(size 1.27 1.27)
				)
			)
		)
		(property "Footprint" ""
			(at 50.8 107.95 0)
			(effects
				(font
					(size 1.27 1.27)
				)
				(hide yes)
			)
		)
		(property "Datasheet" ""
			(at 50.8 107.95 0)
			(effects
				(font
					(size 1.27 1.27)
				)
				(hide yes)
			)
		)
		(property "Description" ""
			(at 50.8 107.95 0)
			(effects
				(font
					(size 1.27 1.27)
				)
				(hide yes)
			)
		)
		(property "Author" "Antmicro"
			(at 59.69 115.57 0)
			(effects
				(font
					(size 1.27 1.27)
					(thickness 0.15)
				)
				(justify left bottom)
				(hide yes)
			)
		)
		(property "License" "Apache-2.0"
			(at 59.69 118.11 0)
			(effects
				(font
					(size 1.27 1.27)
					(thickness 0.15)
				)
				(justify left bottom)
				(hide yes)
			)
		)
		(pin "1"
		)
		(instances
			(project "thunderbolt-gpu-adapter"
				(path ""
					(reference "#PWR0131")
					(unit 1)
				)
			)
		)
	)
	(symbol
		(lib_id "antmicroInterfaceControllers:JHL6340SLLSQ")
		(at 173.99 58.42 0)
		(unit 2)
		(exclude_from_sim no)
		(in_bom yes)
		(on_board yes)
		(dnp no)
		(fields_autoplaced yes)
		(property "Reference" "U4"
			(at 201.93 48.895 0)
			(effects
				(font
					(size 1.27 1.27)
					(thickness 0.15)
				)
			)
		)
		(property "Value" "JHL6340SLLSQ"
			(at 245.11 60.96 0)
			(effects
				(font
					(size 1.27 1.27)
					(thickness 0.15)
				)
				(justify left bottom)
				(hide yes)
			)
		)
		(property "Footprint" "antmicro-footprints:JHL6340SLLSQ"
			(at 245.11 63.5 0)
			(effects
				(font
					(size 1.27 1.27)
					(thickness 0.15)
				)
				(justify left bottom)
				(hide yes)
			)
		)
		(property "Datasheet" "https://www.thunderbolttechnology.net/sites/default/files/18-241_ThunderboltController_Brief_HI.pdf"
			(at 245.11 66.04 0)
			(effects
				(font
					(size 1.27 1.27)
					(thickness 0.15)
				)
				(justify left bottom)
				(hide yes)
			)
		)
		(property "Description" ""
			(at 173.99 58.42 0)
			(effects
				(font
					(size 1.27 1.27)
				)
				(hide yes)
			)
		)
		(property "Manufacturer" "Intel"
			(at 245.11 68.58 0)
			(effects
				(font
					(size 1.27 1.27)
					(thickness 0.15)
				)
				(justify left bottom)
				(hide yes)
			)
		)
		(property "MPN" "JHL6340SLLSQ"
			(at 201.93 51.435 0)
			(effects
				(font
					(size 1.27 1.27)
					(thickness 0.15)
				)
			)
		)
		(property "Author" "Antmicro"
			(at 245.11 73.66 0)
			(effects
				(font
					(size 1.27 1.27)
					(thickness 0.15)
				)
				(justify left bottom)
				(hide yes)
			)
		)
		(property "License" "Apache-2.0"
			(at 245.11 76.2 0)
			(effects
				(font
					(size 1.27 1.27)
					(thickness 0.15)
				)
				(justify left bottom)
				(hide yes)
			)
		)
		(pin "V5"
		)
		(pin "Y9"
		)
		(pin "AC5"
		)
		(pin "F12"
		)
		(pin "L13"
		)
		(pin "A13"
		)
		(pin "T23"
		)
		(pin "AA2"
		)
		(pin "L22"
		)
		(pin "R16"
		)
		(pin "N13"
		)
		(pin "D9"
		)
		(pin "T2"
		)
		(pin "R12"
		)
		(pin "U1"
		)
		(pin "R23"
		)
		(pin "J23"
		)
		(pin "T22"
		)
		(pin "L23"
		)
		(pin "B3"
		)
		(pin "V4"
		)
		(pin "N8"
		)
		(pin "AB11"
		)
		(pin "AB4"
		)
		(pin "M6"
		)
		(pin "K22"
		)
		(pin "R5"
		)
		(pin "L15"
		)
		(pin "F13"
		)
		(pin "L12"
		)
		(pin "H20"
		)
		(pin "V15"
		)
		(pin "V22"
		)
		(pin "V19"
		)
		(pin "P23"
		)
		(pin "M18"
		)
		(pin "A4"
		)
		(pin "A9"
		)
		(pin "M23"
		)
		(pin "Y8"
		)
		(pin "Y4"
		)
		(pin "N5"
		)
		(pin "T5"
		)
		(pin "W1"
		)
		(pin "Y11"
		)
		(pin "Y5"
		)
		(pin "B22"
		)
		(pin "B6"
		)
		(pin "V8"
		)
		(pin "V1"
		)
		(pin "A17"
		)
		(pin "Y2"
		)
		(pin "W2"
		)
		(pin "R22"
		)
		(pin "N6"
		)
		(pin "F16"
		)
		(pin "AB13"
		)
		(pin "H4"
		)
		(pin "F22"
		)
		(pin "R4"
		)
		(pin "F23"
		)
		(pin "W11"
		)
		(pin "D13"
		)
		(pin "AC10"
		)
		(pin "M9"
		)
		(pin "V2"
		)
		(pin "L19"
		)
		(pin "T18"
		)
		(pin "L20"
		)
		(pin "H8"
		)
		(pin "AB7"
		)
		(pin "Y23"
		)
		(pin "K1"
		)
		(pin "AC7"
		)
		(pin "H18"
		)
		(pin "C1"
		)
		(pin "N1"
		)
		(pin "AB5"
		)
		(pin "J5"
		)
		(pin "R15"
		)
		(pin "M13"
		)
		(pin "D1"
		)
		(pin "E20"
		)
		(pin "AC11"
		)
		(pin "A5"
		)
		(pin "AB15"
		)
		(pin "L8"
		)
		(pin "D6"
		)
		(pin "D19"
		)
		(pin "V6"
		)
		(pin "N19"
		)
		(pin "T11"
		)
		(pin "W8"
		)
		(pin "C22"
		)
		(pin "H19"
		)
		(pin "L11"
		)
		(pin "AC13"
		)
		(pin "D2"
		)
		(pin "K23"
		)
		(pin "L2"
		)
		(pin "A7"
		)
		(pin "H16"
		)
		(pin "Y16"
		)
		(pin "V12"
		)
		(pin "AB9"
		)
		(pin "M20"
		)
		(pin "N20"
		)
		(pin "R19"
		)
		(pin "U22"
		)
		(pin "AB21"
		)
		(pin "E4"
		)
		(pin "R6"
		)
		(pin "R20"
		)
		(pin "AC1"
		)
		(pin "G2"
		)
		(pin "M8"
		)
		(pin "M16"
		)
		(pin "V20"
		)
		(pin "F18"
		)
		(pin "AB3"
		)
		(pin "AA1"
		)
		(pin "D22"
		)
		(pin "V11"
		)
		(pin "T1"
		)
		(pin "V18"
		)
		(pin "B9"
		)
		(pin "J9"
		)
		(pin "M5"
		)
		(pin "H15"
		)
		(pin "M12"
		)
		(pin "M15"
		)
		(pin "AC9"
		)
		(pin "W23"
		)
		(pin "V9"
		)
		(pin "B8"
		)
		(pin "N16"
		)
		(pin "B14"
		)
		(pin "AC23"
		)
		(pin "W18"
		)
		(pin "M1"
		)
		(pin "N15"
		)
		(pin "AB17"
		)
		(pin "U23"
		)
		(pin "Y22"
		)
		(pin "L9"
		)
		(pin "T13"
		)
		(pin "F11"
		)
		(pin "N4"
		)
		(pin "F19"
		)
		(pin "W6"
		)
		(pin "F15"
		)
		(pin "B7"
		)
		(pin "Y1"
		)
		(pin "A6"
		)
		(pin "B2"
		)
		(pin "B4"
		)
		(pin "R13"
		)
		(pin "K2"
		)
		(pin "N18"
		)
		(pin "B13"
		)
		(pin "T19"
		)
		(pin "W22"
		)
		(pin "H23"
		)
		(pin "T4"
		)
		(pin "L18"
		)
		(pin "E19"
		)
		(pin "H2"
		)
		(pin "L1"
		)
		(pin "F20"
		)
		(pin "B23"
		)
		(pin "R8"
		)
		(pin "M22"
		)
		(pin "F2"
		)
		(pin "E18"
		)
		(pin "R2"
		)
		(pin "W4"
		)
		(pin "B5"
		)
		(pin "W19"
		)
		(pin "N22"
		)
		(pin "D5"
		)
		(pin "W20"
		)
		(pin "W12"
		)
		(pin "B11"
		)
		(pin "R11"
		)
		(pin "E2"
		)
		(pin "D18"
		)
		(pin "T8"
		)
		(pin "L5"
		)
		(pin "M4"
		)
		(pin "T20"
		)
		(pin "A3"
		)
		(pin "AC3"
		)
		(pin "A19"
		)
		(pin "L16"
		)
		(pin "F4"
		)
		(pin "T12"
		)
		(pin "Y18"
		)
		(pin "T16"
		)
		(pin "AB19"
		)
		(pin "B12"
		)
		(pin "E23"
		)
		(pin "E1"
		)
		(pin "T6"
		)
		(pin "Y19"
		)
		(pin "T15"
		)
		(pin "P22"
		)
		(pin "AB16"
		)
		(pin "AC4"
		)
		(pin "D15"
		)
		(pin "G1"
		)
		(pin "A8"
		)
		(pin "Y12"
		)
		(pin "J4"
		)
		(pin "J1"
		)
		(pin "E22"
		)
		(pin "D20"
		)
		(pin "M2"
		)
		(pin "V23"
		)
		(pin "AB10"
		)
		(pin "AB2"
		)
		(pin "AC15"
		)
		(pin "D23"
		)
		(pin "A23"
		)
		(pin "C23"
		)
		(pin "J2"
		)
		(pin "A21"
		)
		(pin "F1"
		)
		(pin "H5"
		)
		(pin "N11"
		)
		(pin "B20"
		)
		(pin "H22"
		)
		(pin "AA23"
		)
		(pin "E13"
		)
		(pin "J12"
		)
		(pin "W9"
		)
		(pin "H9"
		)
		(pin "B19"
		)
		(pin "AB8"
		)
		(pin "AB22"
		)
		(pin "AB6"
		)
		(pin "AB20"
		)
		(pin "AC2"
		)
		(pin "E9"
		)
		(pin "J11"
		)
		(pin "L4"
		)
		(pin "J8"
		)
		(pin "AC22"
		)
		(pin "J13"
		)
		(pin "N12"
		)
		(pin "J15"
		)
		(pin "B18"
		)
		(pin "Y15"
		)
		(pin "U2"
		)
		(pin "AC12"
		)
		(pin "D16"
		)
		(pin "AB14"
		)
		(pin "AC6"
		)
		(pin "A14"
		)
		(pin "V13"
		)
		(pin "G22"
		)
		(pin "Y13"
		)
		(pin "B16"
		)
		(pin "AB18"
		)
		(pin "B17"
		)
		(pin "A20"
		)
		(pin "AB12"
		)
		(pin "R1"
		)
		(pin "AC20"
		)
		(pin "H12"
		)
		(pin "A2"
		)
		(pin "F5"
		)
		(pin "E6"
		)
		(pin "A10"
		)
		(pin "A12"
		)
		(pin "H11"
		)
		(pin "F9"
		)
		(pin "A1"
		)
		(pin "AB1"
		)
		(pin "E8"
		)
		(pin "A11"
		)
		(pin "L6"
		)
		(pin "B21"
		)
		(pin "AB23"
		)
		(pin "W13"
		)
		(pin "P2"
		)
		(pin "W16"
		)
		(pin "AC16"
		)
		(pin "H6"
		)
		(pin "Y6"
		)
		(pin "A15"
		)
		(pin "J6"
		)
		(pin "V16"
		)
		(pin "N9"
		)
		(pin "AC21"
		)
		(pin "J19"
		)
		(pin "J20"
		)
		(pin "AC17"
		)
		(pin "AC19"
		)
		(pin "M11"
		)
		(pin "D4"
		)
		(pin "P1"
		)
		(pin "W5"
		)
		(pin "R18"
		)
		(pin "E16"
		)
		(pin "N23"
		)
		(pin "A22"
		)
		(pin "R9"
		)
		(pin "D8"
		)
		(pin "E15"
		)
		(pin "M19"
		)
		(pin "Y20"
		)
		(pin "T9"
		)
		(pin "H13"
		)
		(pin "W15"
		)
		(pin "B10"
		)
		(pin "AC14"
		)
		(pin "AC18"
		)
		(pin "C2"
		)
		(pin "E5"
		)
		(pin "J22"
		)
		(pin "J18"
		)
		(pin "J16"
		)
		(pin "AC8"
		)
		(pin "B1"
		)
		(pin "N2"
		)
		(pin "E11"
		)
		(pin "A18"
		)
		(pin "H1"
		)
		(pin "G23"
		)
		(pin "A16"
		)
		(pin "D11"
		)
		(pin "B15"
		)
		(pin "F8"
		)
		(pin "E12"
		)
		(pin "AA22"
		)
		(pin "D12"
		)
		(pin "F6"
		)
		(instances
			(project "thunderbolt-gpu-adapter"
				(path ""
					(reference "U4")
					(unit 2)
				)
			)
		)
	)
	(symbol
		(lib_id "antmicroInterfaceControllers:JHL6340SLLSQ")
		(at 44.45 281.94 0)
		(unit 4)
		(exclude_from_sim no)
		(in_bom yes)
		(on_board yes)
		(dnp no)
		(fields_autoplaced yes)
		(property "Reference" "U4"
			(at 72.39 273.685 0)
			(effects
				(font
					(size 1.27 1.27)
					(thickness 0.15)
				)
			)
		)
		(property "Value" "JHL6340SLLSQ"
			(at 115.57 284.48 0)
			(effects
				(font
					(size 1.27 1.27)
					(thickness 0.15)
				)
				(justify left bottom)
				(hide yes)
			)
		)
		(property "Footprint" "antmicro-footprints:JHL6340SLLSQ"
			(at 115.57 287.02 0)
			(effects
				(font
					(size 1.27 1.27)
					(thickness 0.15)
				)
				(justify left bottom)
				(hide yes)
			)
		)
		(property "Datasheet" "https://www.thunderbolttechnology.net/sites/default/files/18-241_ThunderboltController_Brief_HI.pdf"
			(at 115.57 289.56 0)
			(effects
				(font
					(size 1.27 1.27)
					(thickness 0.15)
				)
				(justify left bottom)
				(hide yes)
			)
		)
		(property "Description" ""
			(at 44.45 281.94 0)
			(effects
				(font
					(size 1.27 1.27)
				)
				(hide yes)
			)
		)
		(property "Manufacturer" "Intel"
			(at 115.57 292.1 0)
			(effects
				(font
					(size 1.27 1.27)
					(thickness 0.15)
				)
				(justify left bottom)
				(hide yes)
			)
		)
		(property "MPN" "JHL6340SLLSQ"
			(at 72.39 276.225 0)
			(effects
				(font
					(size 1.27 1.27)
					(thickness 0.15)
				)
			)
		)
		(property "Author" "Antmicro"
			(at 115.57 297.18 0)
			(effects
				(font
					(size 1.27 1.27)
					(thickness 0.15)
				)
				(justify left bottom)
				(hide yes)
			)
		)
		(property "License" "Apache-2.0"
			(at 115.57 299.72 0)
			(effects
				(font
					(size 1.27 1.27)
					(thickness 0.15)
				)
				(justify left bottom)
				(hide yes)
			)
		)
		(pin "V5"
		)
		(pin "Y9"
		)
		(pin "AC5"
		)
		(pin "F12"
		)
		(pin "L13"
		)
		(pin "A13"
		)
		(pin "T23"
		)
		(pin "AA2"
		)
		(pin "L22"
		)
		(pin "R16"
		)
		(pin "N13"
		)
		(pin "D9"
		)
		(pin "T2"
		)
		(pin "R12"
		)
		(pin "U1"
		)
		(pin "R23"
		)
		(pin "J23"
		)
		(pin "T22"
		)
		(pin "L23"
		)
		(pin "B3"
		)
		(pin "V4"
		)
		(pin "N8"
		)
		(pin "AB11"
		)
		(pin "AB4"
		)
		(pin "M6"
		)
		(pin "K22"
		)
		(pin "R5"
		)
		(pin "L15"
		)
		(pin "F13"
		)
		(pin "L12"
		)
		(pin "H20"
		)
		(pin "V15"
		)
		(pin "V22"
		)
		(pin "V19"
		)
		(pin "P23"
		)
		(pin "M18"
		)
		(pin "A4"
		)
		(pin "A9"
		)
		(pin "M23"
		)
		(pin "Y8"
		)
		(pin "Y4"
		)
		(pin "N5"
		)
		(pin "T5"
		)
		(pin "W1"
		)
		(pin "Y11"
		)
		(pin "Y5"
		)
		(pin "B22"
		)
		(pin "B6"
		)
		(pin "V8"
		)
		(pin "V1"
		)
		(pin "A17"
		)
		(pin "Y2"
		)
		(pin "W2"
		)
		(pin "R22"
		)
		(pin "N6"
		)
		(pin "F16"
		)
		(pin "AB13"
		)
		(pin "H4"
		)
		(pin "F22"
		)
		(pin "R4"
		)
		(pin "F23"
		)
		(pin "W11"
		)
		(pin "D13"
		)
		(pin "AC10"
		)
		(pin "M9"
		)
		(pin "V2"
		)
		(pin "L19"
		)
		(pin "T18"
		)
		(pin "L20"
		)
		(pin "H8"
		)
		(pin "AB7"
		)
		(pin "Y23"
		)
		(pin "K1"
		)
		(pin "AC7"
		)
		(pin "H18"
		)
		(pin "C1"
		)
		(pin "N1"
		)
		(pin "AB5"
		)
		(pin "J5"
		)
		(pin "R15"
		)
		(pin "M13"
		)
		(pin "D1"
		)
		(pin "E20"
		)
		(pin "AC11"
		)
		(pin "A5"
		)
		(pin "AB15"
		)
		(pin "L8"
		)
		(pin "D6"
		)
		(pin "D19"
		)
		(pin "V6"
		)
		(pin "N19"
		)
		(pin "T11"
		)
		(pin "W8"
		)
		(pin "C22"
		)
		(pin "H19"
		)
		(pin "L11"
		)
		(pin "AC13"
		)
		(pin "D2"
		)
		(pin "K23"
		)
		(pin "L2"
		)
		(pin "A7"
		)
		(pin "H16"
		)
		(pin "Y16"
		)
		(pin "V12"
		)
		(pin "AB9"
		)
		(pin "M20"
		)
		(pin "N20"
		)
		(pin "R19"
		)
		(pin "U22"
		)
		(pin "AB21"
		)
		(pin "E4"
		)
		(pin "R6"
		)
		(pin "R20"
		)
		(pin "AC1"
		)
		(pin "G2"
		)
		(pin "M8"
		)
		(pin "M16"
		)
		(pin "V20"
		)
		(pin "F18"
		)
		(pin "AB3"
		)
		(pin "AA1"
		)
		(pin "D22"
		)
		(pin "V11"
		)
		(pin "T1"
		)
		(pin "V18"
		)
		(pin "B9"
		)
		(pin "J9"
		)
		(pin "M5"
		)
		(pin "H15"
		)
		(pin "M12"
		)
		(pin "M15"
		)
		(pin "AC9"
		)
		(pin "W23"
		)
		(pin "V9"
		)
		(pin "B8"
		)
		(pin "N16"
		)
		(pin "B14"
		)
		(pin "AC23"
		)
		(pin "W18"
		)
		(pin "M1"
		)
		(pin "N15"
		)
		(pin "AB17"
		)
		(pin "U23"
		)
		(pin "Y22"
		)
		(pin "L9"
		)
		(pin "T13"
		)
		(pin "F11"
		)
		(pin "N4"
		)
		(pin "F19"
		)
		(pin "W6"
		)
		(pin "F15"
		)
		(pin "B7"
		)
		(pin "Y1"
		)
		(pin "A6"
		)
		(pin "B2"
		)
		(pin "B4"
		)
		(pin "R13"
		)
		(pin "K2"
		)
		(pin "N18"
		)
		(pin "B13"
		)
		(pin "T19"
		)
		(pin "W22"
		)
		(pin "H23"
		)
		(pin "T4"
		)
		(pin "L18"
		)
		(pin "E19"
		)
		(pin "H2"
		)
		(pin "L1"
		)
		(pin "F20"
		)
		(pin "B23"
		)
		(pin "R8"
		)
		(pin "M22"
		)
		(pin "F2"
		)
		(pin "E18"
		)
		(pin "R2"
		)
		(pin "W4"
		)
		(pin "B5"
		)
		(pin "W19"
		)
		(pin "N22"
		)
		(pin "D5"
		)
		(pin "W20"
		)
		(pin "W12"
		)
		(pin "B11"
		)
		(pin "R11"
		)
		(pin "E2"
		)
		(pin "D18"
		)
		(pin "T8"
		)
		(pin "L5"
		)
		(pin "M4"
		)
		(pin "T20"
		)
		(pin "A3"
		)
		(pin "AC3"
		)
		(pin "A19"
		)
		(pin "L16"
		)
		(pin "F4"
		)
		(pin "T12"
		)
		(pin "Y18"
		)
		(pin "T16"
		)
		(pin "AB19"
		)
		(pin "B12"
		)
		(pin "E23"
		)
		(pin "E1"
		)
		(pin "T6"
		)
		(pin "Y19"
		)
		(pin "T15"
		)
		(pin "P22"
		)
		(pin "AB16"
		)
		(pin "AC4"
		)
		(pin "D15"
		)
		(pin "G1"
		)
		(pin "A8"
		)
		(pin "Y12"
		)
		(pin "J4"
		)
		(pin "J1"
		)
		(pin "E22"
		)
		(pin "D20"
		)
		(pin "M2"
		)
		(pin "V23"
		)
		(pin "AB10"
		)
		(pin "AB2"
		)
		(pin "AC15"
		)
		(pin "D23"
		)
		(pin "A23"
		)
		(pin "C23"
		)
		(pin "J2"
		)
		(pin "A21"
		)
		(pin "F1"
		)
		(pin "H5"
		)
		(pin "N11"
		)
		(pin "B20"
		)
		(pin "H22"
		)
		(pin "AA23"
		)
		(pin "E13"
		)
		(pin "J12"
		)
		(pin "W9"
		)
		(pin "H9"
		)
		(pin "B19"
		)
		(pin "AB8"
		)
		(pin "AB22"
		)
		(pin "AB6"
		)
		(pin "AB20"
		)
		(pin "AC2"
		)
		(pin "E9"
		)
		(pin "J11"
		)
		(pin "L4"
		)
		(pin "J8"
		)
		(pin "AC22"
		)
		(pin "J13"
		)
		(pin "N12"
		)
		(pin "J15"
		)
		(pin "B18"
		)
		(pin "Y15"
		)
		(pin "U2"
		)
		(pin "AC12"
		)
		(pin "D16"
		)
		(pin "AB14"
		)
		(pin "AC6"
		)
		(pin "A14"
		)
		(pin "V13"
		)
		(pin "G22"
		)
		(pin "Y13"
		)
		(pin "B16"
		)
		(pin "AB18"
		)
		(pin "B17"
		)
		(pin "A20"
		)
		(pin "AB12"
		)
		(pin "R1"
		)
		(pin "AC20"
		)
		(pin "H12"
		)
		(pin "A2"
		)
		(pin "F5"
		)
		(pin "E6"
		)
		(pin "A10"
		)
		(pin "A12"
		)
		(pin "H11"
		)
		(pin "F9"
		)
		(pin "A1"
		)
		(pin "AB1"
		)
		(pin "E8"
		)
		(pin "A11"
		)
		(pin "L6"
		)
		(pin "B21"
		)
		(pin "AB23"
		)
		(pin "W13"
		)
		(pin "P2"
		)
		(pin "W16"
		)
		(pin "AC16"
		)
		(pin "H6"
		)
		(pin "Y6"
		)
		(pin "A15"
		)
		(pin "J6"
		)
		(pin "V16"
		)
		(pin "N9"
		)
		(pin "AC21"
		)
		(pin "J19"
		)
		(pin "J20"
		)
		(pin "AC17"
		)
		(pin "AC19"
		)
		(pin "M11"
		)
		(pin "D4"
		)
		(pin "P1"
		)
		(pin "W5"
		)
		(pin "R18"
		)
		(pin "E16"
		)
		(pin "N23"
		)
		(pin "A22"
		)
		(pin "R9"
		)
		(pin "D8"
		)
		(pin "E15"
		)
		(pin "M19"
		)
		(pin "Y20"
		)
		(pin "T9"
		)
		(pin "H13"
		)
		(pin "W15"
		)
		(pin "B10"
		)
		(pin "AC14"
		)
		(pin "AC18"
		)
		(pin "C2"
		)
		(pin "E5"
		)
		(pin "J22"
		)
		(pin "J18"
		)
		(pin "J16"
		)
		(pin "AC8"
		)
		(pin "B1"
		)
		(pin "N2"
		)
		(pin "E11"
		)
		(pin "A18"
		)
		(pin "H1"
		)
		(pin "G23"
		)
		(pin "A16"
		)
		(pin "D11"
		)
		(pin "B15"
		)
		(pin "F8"
		)
		(pin "E12"
		)
		(pin "AA22"
		)
		(pin "D12"
		)
		(pin "F6"
		)
		(instances
			(project "thunderbolt-gpu-adapter"
				(path ""
					(reference "U4")
					(unit 4)
				)
			)
		)
	)
	(symbol
		(lib_id "antmicroResistors0402:R_10k_0402")
		(at 182.88 229.87 0)
		(unit 1)
		(exclude_from_sim no)
		(in_bom yes)
		(on_board yes)
		(dnp no)
		(property "Reference" "R85"
			(at 181.61 228.6 0)
			(effects
				(font
					(size 1.27 1.27)
					(thickness 0.15)
				)
			)
		)
		(property "Value" "R_10k_0402"
			(at 203.2 242.57 0)
			(effects
				(font
					(size 1.27 1.27)
					(thickness 0.15)
				)
				(justify left bottom)
				(hide yes)
			)
		)
		(property "Footprint" "antmicro-footprints:R_0402_1005Metric"
			(at 203.2 245.11 0)
			(effects
				(font
					(size 1.27 1.27)
					(thickness 0.15)
				)
				(justify left bottom)
				(hide yes)
			)
		)
		(property "Datasheet" "https://www.bourns.com/docs/product-datasheets/cr.pdf"
			(at 203.2 247.65 0)
			(effects
				(font
					(size 1.27 1.27)
					(thickness 0.15)
				)
				(justify left bottom)
				(hide yes)
			)
		)
		(property "Description" ""
			(at 182.88 229.87 0)
			(effects
				(font
					(size 1.27 1.27)
				)
				(hide yes)
			)
		)
		(property "MPN" "CR0402-FX-1002GLF"
			(at 203.2 250.19 0)
			(effects
				(font
					(size 1.27 1.27)
					(thickness 0.15)
				)
				(justify left bottom)
				(hide yes)
			)
		)
		(property "Manufacturer" "Bourns"
			(at 203.2 252.73 0)
			(effects
				(font
					(size 1.27 1.27)
					(thickness 0.15)
				)
				(justify left bottom)
				(hide yes)
			)
		)
		(property "License" "Apache-2.0"
			(at 203.2 255.27 0)
			(effects
				(font
					(size 1.27 1.27)
					(thickness 0.15)
				)
				(justify left bottom)
				(hide yes)
			)
		)
		(property "Val" "10k"
			(at 189.23 228.6 0)
			(effects
				(font
					(size 1.27 1.27)
					(thickness 0.15)
				)
			)
		)
		(property "Tolerance" "1%"
			(at 203.2 240.03 0)
			(effects
				(font
					(size 1.27 1.27)
				)
				(justify left bottom)
				(hide yes)
			)
		)
		(property "Author" "Antmicro"
			(at 203.2 257.81 0)
			(effects
				(font
					(size 1.27 1.27)
					(thickness 0.15)
				)
				(justify left bottom)
				(hide yes)
			)
		)
		(pin "1"
		)
		(pin "2"
		)
		(instances
			(project "thunderbolt-gpu-adapter"
				(path ""
					(reference "R85")
					(unit 1)
				)
			)
		)
	)
	(symbol
		(lib_id "antmicroCapacitors0402:C_100n_0402")
		(at 39.37 359.41 90)
		(unit 1)
		(exclude_from_sim no)
		(in_bom yes)
		(on_board yes)
		(dnp no)
		(fields_autoplaced yes)
		(property "Reference" "C98"
			(at 41.91 355.5936 90)
			(effects
				(font
					(size 1.27 1.27)
					(thickness 0.15)
				)
				(justify right)
			)
		)
		(property "Value" "C_100n_0402"
			(at 49.53 339.09 0)
			(effects
				(font
					(size 1.27 1.27)
					(thickness 0.15)
				)
				(justify left bottom)
				(hide yes)
			)
		)
		(property "Footprint" "antmicro-footprints:C_0402_1005Metric"
			(at 52.07 339.09 0)
			(effects
				(font
					(size 1.27 1.27)
					(thickness 0.15)
				)
				(justify left bottom)
				(hide yes)
			)
		)
		(property "Datasheet" "https://www.murata.com/products/productdetail?partno=GRM155R61H104KE14%23"
			(at 54.61 339.09 0)
			(effects
				(font
					(size 1.27 1.27)
					(thickness 0.15)
				)
				(justify left bottom)
				(hide yes)
			)
		)
		(property "Description" ""
			(at 39.37 359.41 0)
			(effects
				(font
					(size 1.27 1.27)
				)
				(hide yes)
			)
		)
		(property "MPN" "GRM155R61H104KE14D"
			(at 57.15 339.09 0)
			(effects
				(font
					(size 1.27 1.27)
					(thickness 0.15)
				)
				(justify left bottom)
				(hide yes)
			)
		)
		(property "Manufacturer" "Murata"
			(at 59.69 339.09 0)
			(effects
				(font
					(size 1.27 1.27)
					(thickness 0.15)
				)
				(justify left bottom)
				(hide yes)
			)
		)
		(property "License" "Apache-2.0"
			(at 62.23 339.09 0)
			(effects
				(font
					(size 1.27 1.27)
					(thickness 0.15)
				)
				(justify left bottom)
				(hide yes)
			)
		)
		(property "Val" "100n"
			(at 41.91 358.1336 90)
			(effects
				(font
					(size 1.27 1.27)
					(thickness 0.15)
				)
				(justify right)
			)
		)
		(property "Voltage" "50V"
			(at 67.31 339.09 0)
			(effects
				(font
					(size 1.27 1.27)
				)
				(justify left bottom)
				(hide yes)
			)
		)
		(property "Dielectric" "X5R"
			(at 69.85 339.09 0)
			(effects
				(font
					(size 1.27 1.27)
				)
				(justify left bottom)
				(hide yes)
			)
		)
		(property "Author" "Antmicro"
			(at 64.77 339.09 0)
			(effects
				(font
					(size 1.27 1.27)
					(thickness 0.15)
				)
				(justify left bottom)
				(hide yes)
			)
		)
		(pin "1"
		)
		(pin "2"
		)
		(instances
			(project "thunderbolt-gpu-adapter"
				(path ""
					(reference "C98")
					(unit 1)
				)
			)
		)
	)
	(symbol
		(lib_id "antmicroResistors0402:R_1M_0402")
		(at 129.54 96.52 0)
		(unit 1)
		(exclude_from_sim no)
		(in_bom yes)
		(on_board yes)
		(dnp no)
		(property "Reference" "R71"
			(at 128.27 95.25 0)
			(effects
				(font
					(size 1.27 1.27)
					(thickness 0.15)
				)
			)
		)
		(property "Value" "R_1M_0402"
			(at 149.86 109.22 0)
			(effects
				(font
					(size 1.27 1.27)
					(thickness 0.15)
				)
				(justify left bottom)
				(hide yes)
			)
		)
		(property "Footprint" "antmicro-footprints:R_0402_1005Metric"
			(at 149.86 111.76 0)
			(effects
				(font
					(size 1.27 1.27)
					(thickness 0.15)
				)
				(justify left bottom)
				(hide yes)
			)
		)
		(property "Datasheet" "https://www.bourns.com/docs/product-datasheets/cr.pdf"
			(at 149.86 114.3 0)
			(effects
				(font
					(size 1.27 1.27)
					(thickness 0.15)
				)
				(justify left bottom)
				(hide yes)
			)
		)
		(property "Description" ""
			(at 129.54 96.52 0)
			(effects
				(font
					(size 1.27 1.27)
				)
				(hide yes)
			)
		)
		(property "MPN" "CR0402-FX-1004GLF"
			(at 149.86 116.84 0)
			(effects
				(font
					(size 1.27 1.27)
					(thickness 0.15)
				)
				(justify left bottom)
				(hide yes)
			)
		)
		(property "Manufacturer" "Bourns"
			(at 149.86 119.38 0)
			(effects
				(font
					(size 1.27 1.27)
					(thickness 0.15)
				)
				(justify left bottom)
				(hide yes)
			)
		)
		(property "License" "Apache-2.0"
			(at 149.86 121.92 0)
			(effects
				(font
					(size 1.27 1.27)
					(thickness 0.15)
				)
				(justify left bottom)
				(hide yes)
			)
		)
		(property "Val" "1M"
			(at 132.08 96.52 0)
			(effects
				(font
					(size 1.27 1.27)
					(thickness 0.15)
				)
			)
		)
		(property "Tolerance" "1%"
			(at 149.86 106.68 0)
			(effects
				(font
					(size 1.27 1.27)
				)
				(justify left bottom)
				(hide yes)
			)
		)
		(property "Author" "Antmicro"
			(at 149.86 124.46 0)
			(effects
				(font
					(size 1.27 1.27)
					(thickness 0.15)
				)
				(justify left bottom)
				(hide yes)
			)
		)
		(pin "1"
		)
		(pin "2"
		)
		(instances
			(project "thunderbolt-gpu-adapter"
				(path ""
					(reference "R71")
					(unit 1)
				)
			)
		)
	)
	(symbol
		(lib_id "antmicroClockTimingClockGeneratorsPLLsFrequencySynthesizers:SI52112-B6-GT")
		(at 222.25 358.14 0)
		(unit 1)
		(exclude_from_sim no)
		(in_bom yes)
		(on_board yes)
		(dnp no)
		(fields_autoplaced yes)
		(property "Reference" "U6"
			(at 234.315 350.52 0)
			(effects
				(font
					(size 1.27 1.27)
					(thickness 0.15)
				)
			)
		)
		(property "Value" "SI52112-B6-GT"
			(at 260.35 363.22 0)
			(effects
				(font
					(size 1.27 1.27)
					(thickness 0.15)
				)
				(justify left bottom)
				(hide yes)
			)
		)
		(property "Footprint" "antmicro-footprints:TSSOP-8_3x4.4mm_P0.65mm"
			(at 260.35 365.76 0)
			(effects
				(font
					(size 1.27 1.27)
					(thickness 0.15)
				)
				(justify left bottom)
				(hide yes)
			)
		)
		(property "Datasheet" "https://www.skyworksinc.com/-/media/Skyworks/SL/documents/public/data-sheets/Si52112-B5-B6.pdf"
			(at 260.35 368.3 0)
			(effects
				(font
					(size 1.27 1.27)
					(thickness 0.15)
				)
				(justify left bottom)
				(hide yes)
			)
		)
		(property "Description" ""
			(at 222.25 358.14 0)
			(effects
				(font
					(size 1.27 1.27)
				)
				(hide yes)
			)
		)
		(property "MPN" "SI52112-B6-GT"
			(at 234.315 353.06 0)
			(effects
				(font
					(size 1.27 1.27)
					(thickness 0.15)
				)
			)
		)
		(property "Manufacturer" "Skyworks Solutions"
			(at 260.35 373.38 0)
			(effects
				(font
					(size 1.27 1.27)
					(thickness 0.15)
				)
				(justify left bottom)
				(hide yes)
			)
		)
		(property "License" "Apache-2.0"
			(at 260.35 378.46 0)
			(effects
				(font
					(size 1.27 1.27)
					(thickness 0.15)
				)
				(justify left bottom)
				(hide yes)
			)
		)
		(property "Author" "Antmicro"
			(at 260.35 375.92 0)
			(effects
				(font
					(size 1.27 1.27)
					(thickness 0.15)
				)
				(justify left bottom)
				(hide yes)
			)
		)
		(pin "1"
		)
		(pin "2"
		)
		(pin "3"
		)
		(pin "4"
		)
		(pin "5"
		)
		(pin "6"
		)
		(pin "7"
		)
		(pin "8"
		)
		(instances
			(project "thunderbolt-gpu-adapter"
				(path ""
					(reference "U6")
					(unit 1)
				)
			)
		)
	)
	(symbol
		(lib_id "antmicroResistors0402:R_10k_0402")
		(at 35.56 287.02 0)
		(unit 1)
		(exclude_from_sim no)
		(in_bom yes)
		(on_board yes)
		(dnp no)
		(property "Reference" "R66"
			(at 41.91 285.75 0)
			(effects
				(font
					(size 1.27 1.27)
					(thickness 0.15)
				)
			)
		)
		(property "Value" "R_10k_0402"
			(at 55.88 299.72 0)
			(effects
				(font
					(size 1.27 1.27)
					(thickness 0.15)
				)
				(justify left bottom)
				(hide yes)
			)
		)
		(property "Footprint" "antmicro-footprints:R_0402_1005Metric"
			(at 55.88 302.26 0)
			(effects
				(font
					(size 1.27 1.27)
					(thickness 0.15)
				)
				(justify left bottom)
				(hide yes)
			)
		)
		(property "Datasheet" "https://www.bourns.com/docs/product-datasheets/cr.pdf"
			(at 55.88 304.8 0)
			(effects
				(font
					(size 1.27 1.27)
					(thickness 0.15)
				)
				(justify left bottom)
				(hide yes)
			)
		)
		(property "Description" ""
			(at 35.56 287.02 0)
			(effects
				(font
					(size 1.27 1.27)
				)
				(hide yes)
			)
		)
		(property "MPN" "CR0402-FX-1002GLF"
			(at 55.88 307.34 0)
			(effects
				(font
					(size 1.27 1.27)
					(thickness 0.15)
				)
				(justify left bottom)
				(hide yes)
			)
		)
		(property "Manufacturer" "Bourns"
			(at 55.88 309.88 0)
			(effects
				(font
					(size 1.27 1.27)
					(thickness 0.15)
				)
				(justify left bottom)
				(hide yes)
			)
		)
		(property "License" "Apache-2.0"
			(at 55.88 312.42 0)
			(effects
				(font
					(size 1.27 1.27)
					(thickness 0.15)
				)
				(justify left bottom)
				(hide yes)
			)
		)
		(property "Val" "10k"
			(at 38.1 287.02 0)
			(effects
				(font
					(size 1.27 1.27)
					(thickness 0.15)
				)
			)
		)
		(property "Tolerance" "1%"
			(at 55.88 297.18 0)
			(effects
				(font
					(size 1.27 1.27)
				)
				(justify left bottom)
				(hide yes)
			)
		)
		(property "Author" "Antmicro"
			(at 55.88 314.96 0)
			(effects
				(font
					(size 1.27 1.27)
					(thickness 0.15)
				)
				(justify left bottom)
				(hide yes)
			)
		)
		(pin "1"
		)
		(pin "2"
		)
		(instances
			(project "thunderbolt-gpu-adapter"
				(path ""
					(reference "R66")
					(unit 1)
				)
			)
		)
	)
	(symbol
		(lib_id "antmicroResistors0402:R_100k_0402")
		(at 129.54 99.06 0)
		(unit 1)
		(exclude_from_sim no)
		(in_bom yes)
		(on_board yes)
		(dnp no)
		(property "Reference" "R72"
			(at 128.27 97.79 0)
			(effects
				(font
					(size 1.27 1.27)
					(thickness 0.15)
				)
			)
		)
		(property "Value" "R_100k_0402"
			(at 149.86 111.76 0)
			(effects
				(font
					(size 1.27 1.27)
					(thickness 0.15)
				)
				(justify left bottom)
				(hide yes)
			)
		)
		(property "Footprint" "antmicro-footprints:R_0402_1005Metric"
			(at 149.86 114.3 0)
			(effects
				(font
					(size 1.27 1.27)
					(thickness 0.15)
				)
				(justify left bottom)
				(hide yes)
			)
		)
		(property "Datasheet" "https://www.bourns.com/docs/product-datasheets/cr.pdf"
			(at 149.86 116.84 0)
			(effects
				(font
					(size 1.27 1.27)
					(thickness 0.15)
				)
				(justify left bottom)
				(hide yes)
			)
		)
		(property "Description" ""
			(at 129.54 99.06 0)
			(effects
				(font
					(size 1.27 1.27)
				)
				(hide yes)
			)
		)
		(property "MPN" "CR0402-FX-1003GLF"
			(at 149.86 119.38 0)
			(effects
				(font
					(size 1.27 1.27)
					(thickness 0.15)
				)
				(justify left bottom)
				(hide yes)
			)
		)
		(property "Manufacturer" "Bourns"
			(at 149.86 121.92 0)
			(effects
				(font
					(size 1.27 1.27)
					(thickness 0.15)
				)
				(justify left bottom)
				(hide yes)
			)
		)
		(property "License" "Apache-2.0"
			(at 149.86 124.46 0)
			(effects
				(font
					(size 1.27 1.27)
					(thickness 0.15)
				)
				(justify left bottom)
				(hide yes)
			)
		)
		(property "Val" "100k"
			(at 132.08 100.965 0)
			(effects
				(font
					(size 1.27 1.27)
					(thickness 0.15)
				)
			)
		)
		(property "Tolerance" "1%"
			(at 149.86 109.22 0)
			(effects
				(font
					(size 1.27 1.27)
				)
				(justify left bottom)
				(hide yes)
			)
		)
		(property "Author" "Antmicro"
			(at 149.86 127 0)
			(effects
				(font
					(size 1.27 1.27)
					(thickness 0.15)
				)
				(justify left bottom)
				(hide yes)
			)
		)
		(pin "1"
		)
		(pin "2"
		)
		(instances
			(project "thunderbolt-gpu-adapter"
				(path ""
					(reference "R72")
					(unit 1)
				)
			)
		)
	)
	(symbol
		(lib_id "antmicropower:GND")
		(at 241.3 97.79 0)
		(unit 1)
		(exclude_from_sim no)
		(in_bom yes)
		(on_board yes)
		(dnp no)
		(property "Reference" "#PWR0140"
			(at 241.3 104.14 0)
			(effects
				(font
					(size 1.27 1.27)
				)
				(hide yes)
			)
		)
		(property "Value" "GND"
			(at 241.3 101.6 0)
			(effects
				(font
					(size 1.27 1.27)
				)
			)
		)
		(property "Footprint" ""
			(at 241.3 97.79 0)
			(effects
				(font
					(size 1.27 1.27)
				)
				(hide yes)
			)
		)
		(property "Datasheet" ""
			(at 241.3 97.79 0)
			(effects
				(font
					(size 1.27 1.27)
				)
				(hide yes)
			)
		)
		(property "Description" ""
			(at 241.3 97.79 0)
			(effects
				(font
					(size 1.27 1.27)
				)
				(hide yes)
			)
		)
		(property "Author" "Antmicro"
			(at 250.19 105.41 0)
			(effects
				(font
					(size 1.27 1.27)
					(thickness 0.15)
				)
				(justify left bottom)
				(hide yes)
			)
		)
		(property "License" "Apache-2.0"
			(at 250.19 107.95 0)
			(effects
				(font
					(size 1.27 1.27)
					(thickness 0.15)
				)
				(justify left bottom)
				(hide yes)
			)
		)
		(pin "1"
		)
		(instances
			(project "thunderbolt-gpu-adapter"
				(path ""
					(reference "#PWR0140")
					(unit 1)
				)
			)
		)
	)
	(symbol
		(lib_id "antmicroResistors0402:R_10k_0402")
		(at 182.88 224.79 0)
		(unit 1)
		(exclude_from_sim no)
		(in_bom yes)
		(on_board yes)
		(dnp no)
		(property "Reference" "R83"
			(at 181.61 223.52 0)
			(effects
				(font
					(size 1.27 1.27)
					(thickness 0.15)
				)
			)
		)
		(property "Value" "R_10k_0402"
			(at 203.2 237.49 0)
			(effects
				(font
					(size 1.27 1.27)
					(thickness 0.15)
				)
				(justify left bottom)
				(hide yes)
			)
		)
		(property "Footprint" "antmicro-footprints:R_0402_1005Metric"
			(at 203.2 240.03 0)
			(effects
				(font
					(size 1.27 1.27)
					(thickness 0.15)
				)
				(justify left bottom)
				(hide yes)
			)
		)
		(property "Datasheet" "https://www.bourns.com/docs/product-datasheets/cr.pdf"
			(at 203.2 242.57 0)
			(effects
				(font
					(size 1.27 1.27)
					(thickness 0.15)
				)
				(justify left bottom)
				(hide yes)
			)
		)
		(property "Description" ""
			(at 182.88 224.79 0)
			(effects
				(font
					(size 1.27 1.27)
				)
				(hide yes)
			)
		)
		(property "MPN" "CR0402-FX-1002GLF"
			(at 203.2 245.11 0)
			(effects
				(font
					(size 1.27 1.27)
					(thickness 0.15)
				)
				(justify left bottom)
				(hide yes)
			)
		)
		(property "Manufacturer" "Bourns"
			(at 203.2 247.65 0)
			(effects
				(font
					(size 1.27 1.27)
					(thickness 0.15)
				)
				(justify left bottom)
				(hide yes)
			)
		)
		(property "License" "Apache-2.0"
			(at 203.2 250.19 0)
			(effects
				(font
					(size 1.27 1.27)
					(thickness 0.15)
				)
				(justify left bottom)
				(hide yes)
			)
		)
		(property "Val" "10k"
			(at 189.23 223.52 0)
			(effects
				(font
					(size 1.27 1.27)
					(thickness 0.15)
				)
			)
		)
		(property "Tolerance" "1%"
			(at 203.2 234.95 0)
			(effects
				(font
					(size 1.27 1.27)
				)
				(justify left bottom)
				(hide yes)
			)
		)
		(property "Author" "Antmicro"
			(at 203.2 252.73 0)
			(effects
				(font
					(size 1.27 1.27)
					(thickness 0.15)
				)
				(justify left bottom)
				(hide yes)
			)
		)
		(pin "1"
		)
		(pin "2"
		)
		(instances
			(project "thunderbolt-gpu-adapter"
				(path ""
					(reference "R83")
					(unit 1)
				)
			)
		)
	)
	(symbol
		(lib_id "antmicropower:GND")
		(at 243.84 308.61 0)
		(unit 1)
		(exclude_from_sim no)
		(in_bom yes)
		(on_board yes)
		(dnp no)
		(property "Reference" "#PWR0136"
			(at 243.84 314.96 0)
			(effects
				(font
					(size 1.27 1.27)
				)
				(hide yes)
			)
		)
		(property "Value" "GND"
			(at 243.84 312.42 0)
			(effects
				(font
					(size 1.27 1.27)
				)
			)
		)
		(property "Footprint" ""
			(at 243.84 308.61 0)
			(effects
				(font
					(size 1.27 1.27)
				)
				(hide yes)
			)
		)
		(property "Datasheet" ""
			(at 243.84 308.61 0)
			(effects
				(font
					(size 1.27 1.27)
				)
				(hide yes)
			)
		)
		(property "Description" ""
			(at 243.84 308.61 0)
			(effects
				(font
					(size 1.27 1.27)
				)
				(hide yes)
			)
		)
		(property "Author" "Antmicro"
			(at 252.73 316.23 0)
			(effects
				(font
					(size 1.27 1.27)
					(thickness 0.15)
				)
				(justify left bottom)
				(hide yes)
			)
		)
		(property "License" "Apache-2.0"
			(at 252.73 318.77 0)
			(effects
				(font
					(size 1.27 1.27)
					(thickness 0.15)
				)
				(justify left bottom)
				(hide yes)
			)
		)
		(pin "1"
		)
		(instances
			(project "thunderbolt-gpu-adapter"
				(path ""
					(reference "#PWR0136")
					(unit 1)
				)
			)
		)
	)
	(symbol
		(lib_id "antmicroResistors0402:R_14k_0402")
		(at 182.88 186.69 0)
		(unit 1)
		(exclude_from_sim no)
		(in_bom yes)
		(on_board yes)
		(dnp yes)
		(fields_autoplaced yes)
		(property "Reference" "R76"
			(at 185.42 190.5 0)
			(effects
				(font
					(size 1.27 1.27)
					(thickness 0.15)
				)
			)
		)
		(property "Value" "R_14k_0402"
			(at 203.2 199.39 0)
			(effects
				(font
					(size 1.27 1.27)
					(thickness 0.15)
				)
				(justify left bottom)
				(hide yes)
			)
		)
		(property "Footprint" "antmicro-footprints:R_0402_1005Metric"
			(at 203.2 201.93 0)
			(effects
				(font
					(size 1.27 1.27)
					(thickness 0.15)
				)
				(justify left bottom)
				(hide yes)
			)
		)
		(property "Datasheet" "https://www.bourns.com/docs/product-datasheets/cr.pdf"
			(at 203.2 204.47 0)
			(effects
				(font
					(size 1.27 1.27)
					(thickness 0.15)
				)
				(justify left bottom)
				(hide yes)
			)
		)
		(property "Description" ""
			(at 182.88 186.69 0)
			(effects
				(font
					(size 1.27 1.27)
				)
				(hide yes)
			)
		)
		(property "MPN" "CR0402-FX-1402GLF"
			(at 203.2 207.01 0)
			(effects
				(font
					(size 1.27 1.27)
					(thickness 0.15)
				)
				(justify left bottom)
				(hide yes)
			)
		)
		(property "Manufacturer" "Bourns"
			(at 203.2 209.55 0)
			(effects
				(font
					(size 1.27 1.27)
					(thickness 0.15)
				)
				(justify left bottom)
				(hide yes)
			)
		)
		(property "License" "Apache-2.0"
			(at 203.2 212.09 0)
			(effects
				(font
					(size 1.27 1.27)
					(thickness 0.15)
				)
				(justify left bottom)
				(hide yes)
			)
		)
		(property "Val" "14k"
			(at 185.42 193.04 0)
			(effects
				(font
					(size 1.27 1.27)
					(thickness 0.15)
				)
			)
		)
		(property "Tolerance" "1%"
			(at 203.2 196.85 0)
			(effects
				(font
					(size 1.27 1.27)
				)
				(justify left bottom)
				(hide yes)
			)
		)
		(property "Author" "Antmicro"
			(at 203.2 214.63 0)
			(effects
				(font
					(size 1.27 1.27)
					(thickness 0.15)
				)
				(justify left bottom)
				(hide yes)
			)
		)
		(pin "1"
		)
		(pin "2"
		)
		(instances
			(project "thunderbolt-gpu-adapter"
				(path ""
					(reference "R76")
					(unit 1)
				)
			)
		)
	)
	(symbol
		(lib_id "antmicroCapacitors0402:C_10p_0402")
		(at 142.24 288.29 0)
		(unit 1)
		(exclude_from_sim no)
		(in_bom yes)
		(on_board yes)
		(dnp no)
		(fields_autoplaced yes)
		(property "Reference" "C116"
			(at 144.7863 281.305 0)
			(effects
				(font
					(size 1.27 1.27)
					(thickness 0.15)
				)
			)
		)
		(property "Value" "C_10p_0402"
			(at 162.56 298.45 0)
			(effects
				(font
					(size 1.27 1.27)
					(thickness 0.15)
				)
				(justify left bottom)
				(hide yes)
			)
		)
		(property "Footprint" "antmicro-footprints:C_0402_1005Metric"
			(at 162.56 300.99 0)
			(effects
				(font
					(size 1.27 1.27)
					(thickness 0.15)
				)
				(justify left bottom)
				(hide yes)
			)
		)
		(property "Datasheet" "https://www.murata.com/products/productdetail?partno=GCM1555C1H100GA16%23"
			(at 162.56 303.53 0)
			(effects
				(font
					(size 1.27 1.27)
					(thickness 0.15)
				)
				(justify left bottom)
				(hide yes)
			)
		)
		(property "Description" ""
			(at 142.24 288.29 0)
			(effects
				(font
					(size 1.27 1.27)
				)
				(hide yes)
			)
		)
		(property "MPN" "GCM1555C1H100GA16D"
			(at 162.56 306.07 0)
			(effects
				(font
					(size 1.27 1.27)
					(thickness 0.15)
				)
				(justify left bottom)
				(hide yes)
			)
		)
		(property "Manufacturer" "Murata"
			(at 162.56 308.61 0)
			(effects
				(font
					(size 1.27 1.27)
					(thickness 0.15)
				)
				(justify left bottom)
				(hide yes)
			)
		)
		(property "License" "Apache-2.0"
			(at 162.56 311.15 0)
			(effects
				(font
					(size 1.27 1.27)
					(thickness 0.15)
				)
				(justify left bottom)
				(hide yes)
			)
		)
		(property "Val" "10p"
			(at 144.7863 283.845 0)
			(effects
				(font
					(size 1.27 1.27)
					(thickness 0.15)
				)
			)
		)
		(property "Voltage" "50V"
			(at 162.56 316.23 0)
			(effects
				(font
					(size 1.27 1.27)
				)
				(justify left bottom)
				(hide yes)
			)
		)
		(property "Dielectric" "C0G"
			(at 162.56 318.77 0)
			(effects
				(font
					(size 1.27 1.27)
				)
				(justify left bottom)
				(hide yes)
			)
		)
		(property "Author" "Antmicro"
			(at 162.56 313.69 0)
			(effects
				(font
					(size 1.27 1.27)
					(thickness 0.15)
				)
				(justify left bottom)
				(hide yes)
			)
		)
		(pin "1"
		)
		(pin "2"
		)
		(instances
			(project "thunderbolt-gpu-adapter"
				(path ""
					(reference "C116")
					(unit 1)
				)
			)
		)
	)
	(symbol
		(lib_id "antmicroResistors0402:R_499R_0402")
		(at 63.5 104.14 0)
		(unit 1)
		(exclude_from_sim no)
		(in_bom yes)
		(on_board yes)
		(dnp no)
		(fields_autoplaced yes)
		(property "Reference" "R68"
			(at 66.04 107.95 0)
			(effects
				(font
					(size 1.27 1.27)
					(thickness 0.15)
				)
			)
		)
		(property "Value" "R_499R_0402"
			(at 83.82 116.84 0)
			(effects
				(font
					(size 1.27 1.27)
					(thickness 0.15)
				)
				(justify left bottom)
				(hide yes)
			)
		)
		(property "Footprint" "antmicro-footprints:R_0402_1005Metric"
			(at 83.82 119.38 0)
			(effects
				(font
					(size 1.27 1.27)
					(thickness 0.15)
				)
				(justify left bottom)
				(hide yes)
			)
		)
		(property "Datasheet" "https://www.mouser.com/datasheet/2/54/cr-1858361.pdf"
			(at 83.82 121.92 0)
			(effects
				(font
					(size 1.27 1.27)
					(thickness 0.15)
				)
				(justify left bottom)
				(hide yes)
			)
		)
		(property "Description" ""
			(at 63.5 104.14 0)
			(effects
				(font
					(size 1.27 1.27)
				)
				(hide yes)
			)
		)
		(property "MPN" "CR0402-FX-4990GLF"
			(at 83.82 124.46 0)
			(effects
				(font
					(size 1.27 1.27)
					(thickness 0.15)
				)
				(justify left bottom)
				(hide yes)
			)
		)
		(property "Manufacturer" "Bourns"
			(at 83.82 127 0)
			(effects
				(font
					(size 1.27 1.27)
					(thickness 0.15)
				)
				(justify left bottom)
				(hide yes)
			)
		)
		(property "License" "Apache-2.0"
			(at 83.82 129.54 0)
			(effects
				(font
					(size 1.27 1.27)
					(thickness 0.15)
				)
				(justify left bottom)
				(hide yes)
			)
		)
		(property "Val" "499R"
			(at 66.04 110.49 0)
			(effects
				(font
					(size 1.27 1.27)
					(thickness 0.15)
				)
			)
		)
		(property "Tolerance" "1%"
			(at 83.82 114.3 0)
			(effects
				(font
					(size 1.27 1.27)
				)
				(justify left bottom)
				(hide yes)
			)
		)
		(property "Author" "Antmicro"
			(at 83.82 132.08 0)
			(effects
				(font
					(size 1.27 1.27)
					(thickness 0.15)
				)
				(justify left bottom)
				(hide yes)
			)
		)
		(pin "1"
		)
		(pin "2"
		)
		(instances
			(project "thunderbolt-gpu-adapter"
				(path ""
					(reference "R68")
					(unit 1)
				)
			)
		)
	)
	(symbol
		(lib_id "antmicroCapacitors0402:C_220n_0402")
		(at 250.19 58.42 0)
		(unit 1)
		(exclude_from_sim no)
		(in_bom yes)
		(on_board yes)
		(dnp no)
		(property "Reference" "C109"
			(at 256.54 57.15 0)
			(effects
				(font
					(size 1.27 1.27)
					(thickness 0.15)
				)
			)
		)
		(property "Value" "C_220n_0402"
			(at 270.51 68.58 0)
			(effects
				(font
					(size 1.27 1.27)
					(thickness 0.15)
				)
				(justify left bottom)
				(hide yes)
			)
		)
		(property "Footprint" "antmicro-footprints:C_0402_1005Metric"
			(at 270.51 71.12 0)
			(effects
				(font
					(size 1.27 1.27)
					(thickness 0.15)
				)
				(justify left bottom)
				(hide yes)
			)
		)
		(property "Datasheet" "https://www.yageo.com/en/Chart/Download/pdf/CC0402KRX5R6BB224"
			(at 270.51 73.66 0)
			(effects
				(font
					(size 1.27 1.27)
					(thickness 0.15)
				)
				(justify left bottom)
				(hide yes)
			)
		)
		(property "Description" ""
			(at 250.19 58.42 0)
			(effects
				(font
					(size 1.27 1.27)
				)
				(hide yes)
			)
		)
		(property "MPN" "CC0402KRX5R6BB224"
			(at 270.51 76.2 0)
			(effects
				(font
					(size 1.27 1.27)
					(thickness 0.15)
				)
				(justify left bottom)
				(hide yes)
			)
		)
		(property "Manufacturer" "YAGEO"
			(at 270.51 78.74 0)
			(effects
				(font
					(size 1.27 1.27)
					(thickness 0.15)
				)
				(justify left bottom)
				(hide yes)
			)
		)
		(property "License" "Apache-2.0"
			(at 270.51 81.28 0)
			(effects
				(font
					(size 1.27 1.27)
					(thickness 0.15)
				)
				(justify left bottom)
				(hide yes)
			)
		)
		(property "Val" "220n"
			(at 256.54 59.69 0)
			(effects
				(font
					(size 1.27 1.27)
					(thickness 0.15)
				)
			)
		)
		(property "Voltage" ""
			(at 270.51 86.36 0)
			(effects
				(font
					(size 1.27 1.27)
				)
				(justify left bottom)
				(hide yes)
			)
		)
		(property "Dielectric" ""
			(at 270.51 88.9 0)
			(effects
				(font
					(size 1.27 1.27)
				)
				(justify left bottom)
				(hide yes)
			)
		)
		(property "Author" "Antmicro"
			(at 270.51 83.82 0)
			(effects
				(font
					(size 1.27 1.27)
					(thickness 0.15)
				)
				(justify left bottom)
				(hide yes)
			)
		)
		(pin "1"
		)
		(pin "2"
		)
		(instances
			(project "thunderbolt-gpu-adapter"
				(path ""
					(reference "C109")
					(unit 1)
				)
			)
		)
	)
	(symbol
		(lib_id "antmicroResistors0402:R_3k3_0402")
		(at 120.65 365.76 90)
		(unit 1)
		(exclude_from_sim no)
		(in_bom yes)
		(on_board yes)
		(dnp no)
		(fields_autoplaced yes)
		(property "Reference" "R52"
			(at 122.555 361.95 90)
			(effects
				(font
					(size 1.27 1.27)
					(thickness 0.15)
				)
				(justify right)
			)
		)
		(property "Value" "R_3k3_0402"
			(at 133.35 345.44 0)
			(effects
				(font
					(size 1.27 1.27)
					(thickness 0.15)
				)
				(justify left bottom)
				(hide yes)
			)
		)
		(property "Footprint" "antmicro-footprints:R_0402_1005Metric"
			(at 135.89 345.44 0)
			(effects
				(font
					(size 1.27 1.27)
					(thickness 0.15)
				)
				(justify left bottom)
				(hide yes)
			)
		)
		(property "Datasheet" "https://www.bourns.com/docs/product-datasheets/cr.pdf"
			(at 138.43 345.44 0)
			(effects
				(font
					(size 1.27 1.27)
					(thickness 0.15)
				)
				(justify left bottom)
				(hide yes)
			)
		)
		(property "Description" ""
			(at 120.65 365.76 0)
			(effects
				(font
					(size 1.27 1.27)
				)
				(hide yes)
			)
		)
		(property "MPN" "CR0402-FX-3301GLF"
			(at 140.97 345.44 0)
			(effects
				(font
					(size 1.27 1.27)
					(thickness 0.15)
				)
				(justify left bottom)
				(hide yes)
			)
		)
		(property "Manufacturer" "Bourns"
			(at 143.51 345.44 0)
			(effects
				(font
					(size 1.27 1.27)
					(thickness 0.15)
				)
				(justify left bottom)
				(hide yes)
			)
		)
		(property "License" "Apache-2.0"
			(at 146.05 345.44 0)
			(effects
				(font
					(size 1.27 1.27)
					(thickness 0.15)
				)
				(justify left bottom)
				(hide yes)
			)
		)
		(property "Val" "3k3"
			(at 122.555 364.49 90)
			(effects
				(font
					(size 1.27 1.27)
					(thickness 0.15)
				)
				(justify right)
			)
		)
		(property "Tolerance" "1%"
			(at 130.81 345.44 0)
			(effects
				(font
					(size 1.27 1.27)
				)
				(justify left bottom)
				(hide yes)
			)
		)
		(property "Author" "Antmicro"
			(at 148.59 345.44 0)
			(effects
				(font
					(size 1.27 1.27)
					(thickness 0.15)
				)
				(justify left bottom)
				(hide yes)
			)
		)
		(pin "1"
		)
		(pin "2"
		)
		(instances
			(project "thunderbolt-gpu-adapter"
				(path ""
					(reference "R52")
					(unit 1)
				)
			)
		)
	)
	(symbol
		(lib_id "antmicroResistors0402:R_100k_0402")
		(at 182.88 237.49 0)
		(unit 1)
		(exclude_from_sim no)
		(in_bom yes)
		(on_board yes)
		(dnp no)
		(property "Reference" "R87"
			(at 181.61 236.22 0)
			(effects
				(font
					(size 1.27 1.27)
					(thickness 0.15)
				)
			)
		)
		(property "Value" "R_100k_0402"
			(at 203.2 250.19 0)
			(effects
				(font
					(size 1.27 1.27)
					(thickness 0.15)
				)
				(justify left bottom)
				(hide yes)
			)
		)
		(property "Footprint" "antmicro-footprints:R_0402_1005Metric"
			(at 203.2 252.73 0)
			(effects
				(font
					(size 1.27 1.27)
					(thickness 0.15)
				)
				(justify left bottom)
				(hide yes)
			)
		)
		(property "Datasheet" "https://www.bourns.com/docs/product-datasheets/cr.pdf"
			(at 203.2 255.27 0)
			(effects
				(font
					(size 1.27 1.27)
					(thickness 0.15)
				)
				(justify left bottom)
				(hide yes)
			)
		)
		(property "Description" ""
			(at 182.88 237.49 0)
			(effects
				(font
					(size 1.27 1.27)
				)
				(hide yes)
			)
		)
		(property "MPN" "CR0402-FX-1003GLF"
			(at 203.2 257.81 0)
			(effects
				(font
					(size 1.27 1.27)
					(thickness 0.15)
				)
				(justify left bottom)
				(hide yes)
			)
		)
		(property "Manufacturer" "Bourns"
			(at 203.2 260.35 0)
			(effects
				(font
					(size 1.27 1.27)
					(thickness 0.15)
				)
				(justify left bottom)
				(hide yes)
			)
		)
		(property "License" "Apache-2.0"
			(at 203.2 262.89 0)
			(effects
				(font
					(size 1.27 1.27)
					(thickness 0.15)
				)
				(justify left bottom)
				(hide yes)
			)
		)
		(property "Val" "100k"
			(at 189.865 236.22 0)
			(effects
				(font
					(size 1.27 1.27)
					(thickness 0.15)
				)
			)
		)
		(property "Tolerance" "1%"
			(at 203.2 247.65 0)
			(effects
				(font
					(size 1.27 1.27)
				)
				(justify left bottom)
				(hide yes)
			)
		)
		(property "Author" "Antmicro"
			(at 203.2 265.43 0)
			(effects
				(font
					(size 1.27 1.27)
					(thickness 0.15)
				)
				(justify left bottom)
				(hide yes)
			)
		)
		(pin "1"
		)
		(pin "2"
		)
		(instances
			(project "thunderbolt-gpu-adapter"
				(path ""
					(reference "R87")
					(unit 1)
				)
			)
		)
	)
	(symbol
		(lib_id "antmicroResistors0402:R_3k3_0402")
		(at 129.54 379.73 180)
		(unit 1)
		(exclude_from_sim no)
		(in_bom yes)
		(on_board yes)
		(dnp no)
		(fields_autoplaced yes)
		(property "Reference" "R53"
			(at 120.65 378.46 0)
			(effects
				(font
					(size 1.27 1.27)
					(thickness 0.15)
				)
				(justify right)
			)
		)
		(property "Value" "R_3k3_0402"
			(at 109.22 367.03 0)
			(effects
				(font
					(size 1.27 1.27)
					(thickness 0.15)
				)
				(justify left bottom)
				(hide yes)
			)
		)
		(property "Footprint" "antmicro-footprints:R_0402_1005Metric"
			(at 109.22 364.49 0)
			(effects
				(font
					(size 1.27 1.27)
					(thickness 0.15)
				)
				(justify left bottom)
				(hide yes)
			)
		)
		(property "Datasheet" "https://www.bourns.com/docs/product-datasheets/cr.pdf"
			(at 109.22 361.95 0)
			(effects
				(font
					(size 1.27 1.27)
					(thickness 0.15)
				)
				(justify left bottom)
				(hide yes)
			)
		)
		(property "Description" ""
			(at 129.54 379.73 0)
			(effects
				(font
					(size 1.27 1.27)
				)
				(hide yes)
			)
		)
		(property "MPN" "CR0402-FX-3301GLF"
			(at 109.22 359.41 0)
			(effects
				(font
					(size 1.27 1.27)
					(thickness 0.15)
				)
				(justify left bottom)
				(hide yes)
			)
		)
		(property "Manufacturer" "Bourns"
			(at 109.22 356.87 0)
			(effects
				(font
					(size 1.27 1.27)
					(thickness 0.15)
				)
				(justify left bottom)
				(hide yes)
			)
		)
		(property "License" "Apache-2.0"
			(at 109.22 354.33 0)
			(effects
				(font
					(size 1.27 1.27)
					(thickness 0.15)
				)
				(justify left bottom)
				(hide yes)
			)
		)
		(property "Val" "3k3"
			(at 129.54 378.46 0)
			(effects
				(font
					(size 1.27 1.27)
					(thickness 0.15)
				)
				(justify right)
			)
		)
		(property "Tolerance" "1%"
			(at 109.22 369.57 0)
			(effects
				(font
					(size 1.27 1.27)
				)
				(justify left bottom)
				(hide yes)
			)
		)
		(property "Author" "Antmicro"
			(at 109.22 351.79 0)
			(effects
				(font
					(size 1.27 1.27)
					(thickness 0.15)
				)
				(justify left bottom)
				(hide yes)
			)
		)
		(pin "1"
		)
		(pin "2"
		)
		(instances
			(project "thunderbolt-gpu-adapter"
				(path ""
					(reference "R53")
					(unit 1)
				)
			)
		)
	)
	(symbol
		(lib_id "antmicroResistors0402:R_14k_0402")
		(at 114.3 247.65 0)
		(unit 1)
		(exclude_from_sim no)
		(in_bom yes)
		(on_board yes)
		(dnp yes)
		(fields_autoplaced yes)
		(property "Reference" "R63"
			(at 116.84 251.46 0)
			(effects
				(font
					(size 1.27 1.27)
					(thickness 0.15)
				)
			)
		)
		(property "Value" "R_14k_0402"
			(at 134.62 260.35 0)
			(effects
				(font
					(size 1.27 1.27)
					(thickness 0.15)
				)
				(justify left bottom)
				(hide yes)
			)
		)
		(property "Footprint" "antmicro-footprints:R_0402_1005Metric"
			(at 134.62 262.89 0)
			(effects
				(font
					(size 1.27 1.27)
					(thickness 0.15)
				)
				(justify left bottom)
				(hide yes)
			)
		)
		(property "Datasheet" "https://www.bourns.com/docs/product-datasheets/cr.pdf"
			(at 134.62 265.43 0)
			(effects
				(font
					(size 1.27 1.27)
					(thickness 0.15)
				)
				(justify left bottom)
				(hide yes)
			)
		)
		(property "Description" ""
			(at 114.3 247.65 0)
			(effects
				(font
					(size 1.27 1.27)
				)
				(hide yes)
			)
		)
		(property "MPN" "CR0402-FX-1402GLF"
			(at 134.62 267.97 0)
			(effects
				(font
					(size 1.27 1.27)
					(thickness 0.15)
				)
				(justify left bottom)
				(hide yes)
			)
		)
		(property "Manufacturer" "Bourns"
			(at 134.62 270.51 0)
			(effects
				(font
					(size 1.27 1.27)
					(thickness 0.15)
				)
				(justify left bottom)
				(hide yes)
			)
		)
		(property "License" "Apache-2.0"
			(at 134.62 273.05 0)
			(effects
				(font
					(size 1.27 1.27)
					(thickness 0.15)
				)
				(justify left bottom)
				(hide yes)
			)
		)
		(property "Val" "14k"
			(at 116.84 254 0)
			(effects
				(font
					(size 1.27 1.27)
					(thickness 0.15)
				)
			)
		)
		(property "Tolerance" "1%"
			(at 134.62 257.81 0)
			(effects
				(font
					(size 1.27 1.27)
				)
				(justify left bottom)
				(hide yes)
			)
		)
		(property "Author" "Antmicro"
			(at 134.62 275.59 0)
			(effects
				(font
					(size 1.27 1.27)
					(thickness 0.15)
				)
				(justify left bottom)
				(hide yes)
			)
		)
		(pin "1"
		)
		(pin "2"
		)
		(instances
			(project "thunderbolt-gpu-adapter"
				(path ""
					(reference "R63")
					(unit 1)
				)
			)
		)
	)
	(symbol
		(lib_id "antmicroInterfaceControllers:JHL6340SLLSQ")
		(at 123.19 143.51 0)
		(unit 3)
		(exclude_from_sim no)
		(in_bom yes)
		(on_board yes)
		(dnp no)
		(fields_autoplaced yes)
		(property "Reference" "U4"
			(at 151.13 135.255 0)
			(effects
				(font
					(size 1.27 1.27)
					(thickness 0.15)
				)
			)
		)
		(property "Value" "JHL6340SLLSQ"
			(at 194.31 146.05 0)
			(effects
				(font
					(size 1.27 1.27)
					(thickness 0.15)
				)
				(justify left bottom)
				(hide yes)
			)
		)
		(property "Footprint" "antmicro-footprints:JHL6340SLLSQ"
			(at 194.31 148.59 0)
			(effects
				(font
					(size 1.27 1.27)
					(thickness 0.15)
				)
				(justify left bottom)
				(hide yes)
			)
		)
		(property "Datasheet" "https://www.thunderbolttechnology.net/sites/default/files/18-241_ThunderboltController_Brief_HI.pdf"
			(at 194.31 151.13 0)
			(effects
				(font
					(size 1.27 1.27)
					(thickness 0.15)
				)
				(justify left bottom)
				(hide yes)
			)
		)
		(property "Description" ""
			(at 123.19 143.51 0)
			(effects
				(font
					(size 1.27 1.27)
				)
				(hide yes)
			)
		)
		(property "Manufacturer" "Intel"
			(at 194.31 153.67 0)
			(effects
				(font
					(size 1.27 1.27)
					(thickness 0.15)
				)
				(justify left bottom)
				(hide yes)
			)
		)
		(property "MPN" "JHL6340SLLSQ"
			(at 151.13 137.795 0)
			(effects
				(font
					(size 1.27 1.27)
					(thickness 0.15)
				)
			)
		)
		(property "Author" "Antmicro"
			(at 194.31 158.75 0)
			(effects
				(font
					(size 1.27 1.27)
					(thickness 0.15)
				)
				(justify left bottom)
				(hide yes)
			)
		)
		(property "License" "Apache-2.0"
			(at 194.31 161.29 0)
			(effects
				(font
					(size 1.27 1.27)
					(thickness 0.15)
				)
				(justify left bottom)
				(hide yes)
			)
		)
		(pin "V5"
		)
		(pin "Y9"
		)
		(pin "AC5"
		)
		(pin "F12"
		)
		(pin "L13"
		)
		(pin "A13"
		)
		(pin "T23"
		)
		(pin "AA2"
		)
		(pin "L22"
		)
		(pin "R16"
		)
		(pin "N13"
		)
		(pin "D9"
		)
		(pin "T2"
		)
		(pin "R12"
		)
		(pin "U1"
		)
		(pin "R23"
		)
		(pin "J23"
		)
		(pin "T22"
		)
		(pin "L23"
		)
		(pin "B3"
		)
		(pin "V4"
		)
		(pin "N8"
		)
		(pin "AB11"
		)
		(pin "AB4"
		)
		(pin "M6"
		)
		(pin "K22"
		)
		(pin "R5"
		)
		(pin "L15"
		)
		(pin "F13"
		)
		(pin "L12"
		)
		(pin "H20"
		)
		(pin "V15"
		)
		(pin "V22"
		)
		(pin "V19"
		)
		(pin "P23"
		)
		(pin "M18"
		)
		(pin "A4"
		)
		(pin "A9"
		)
		(pin "M23"
		)
		(pin "Y8"
		)
		(pin "Y4"
		)
		(pin "N5"
		)
		(pin "T5"
		)
		(pin "W1"
		)
		(pin "Y11"
		)
		(pin "Y5"
		)
		(pin "B22"
		)
		(pin "B6"
		)
		(pin "V8"
		)
		(pin "V1"
		)
		(pin "A17"
		)
		(pin "Y2"
		)
		(pin "W2"
		)
		(pin "R22"
		)
		(pin "N6"
		)
		(pin "F16"
		)
		(pin "AB13"
		)
		(pin "H4"
		)
		(pin "F22"
		)
		(pin "R4"
		)
		(pin "F23"
		)
		(pin "W11"
		)
		(pin "D13"
		)
		(pin "AC10"
		)
		(pin "M9"
		)
		(pin "V2"
		)
		(pin "L19"
		)
		(pin "T18"
		)
		(pin "L20"
		)
		(pin "H8"
		)
		(pin "AB7"
		)
		(pin "Y23"
		)
		(pin "K1"
		)
		(pin "AC7"
		)
		(pin "H18"
		)
		(pin "C1"
		)
		(pin "N1"
		)
		(pin "AB5"
		)
		(pin "J5"
		)
		(pin "R15"
		)
		(pin "M13"
		)
		(pin "D1"
		)
		(pin "E20"
		)
		(pin "AC11"
		)
		(pin "A5"
		)
		(pin "AB15"
		)
		(pin "L8"
		)
		(pin "D6"
		)
		(pin "D19"
		)
		(pin "V6"
		)
		(pin "N19"
		)
		(pin "T11"
		)
		(pin "W8"
		)
		(pin "C22"
		)
		(pin "H19"
		)
		(pin "L11"
		)
		(pin "AC13"
		)
		(pin "D2"
		)
		(pin "K23"
		)
		(pin "L2"
		)
		(pin "A7"
		)
		(pin "H16"
		)
		(pin "Y16"
		)
		(pin "V12"
		)
		(pin "AB9"
		)
		(pin "M20"
		)
		(pin "N20"
		)
		(pin "R19"
		)
		(pin "U22"
		)
		(pin "AB21"
		)
		(pin "E4"
		)
		(pin "R6"
		)
		(pin "R20"
		)
		(pin "AC1"
		)
		(pin "G2"
		)
		(pin "M8"
		)
		(pin "M16"
		)
		(pin "V20"
		)
		(pin "F18"
		)
		(pin "AB3"
		)
		(pin "AA1"
		)
		(pin "D22"
		)
		(pin "V11"
		)
		(pin "T1"
		)
		(pin "V18"
		)
		(pin "B9"
		)
		(pin "J9"
		)
		(pin "M5"
		)
		(pin "H15"
		)
		(pin "M12"
		)
		(pin "M15"
		)
		(pin "AC9"
		)
		(pin "W23"
		)
		(pin "V9"
		)
		(pin "B8"
		)
		(pin "N16"
		)
		(pin "B14"
		)
		(pin "AC23"
		)
		(pin "W18"
		)
		(pin "M1"
		)
		(pin "N15"
		)
		(pin "AB17"
		)
		(pin "U23"
		)
		(pin "Y22"
		)
		(pin "L9"
		)
		(pin "T13"
		)
		(pin "F11"
		)
		(pin "N4"
		)
		(pin "F19"
		)
		(pin "W6"
		)
		(pin "F15"
		)
		(pin "B7"
		)
		(pin "Y1"
		)
		(pin "A6"
		)
		(pin "B2"
		)
		(pin "B4"
		)
		(pin "R13"
		)
		(pin "K2"
		)
		(pin "N18"
		)
		(pin "B13"
		)
		(pin "T19"
		)
		(pin "W22"
		)
		(pin "H23"
		)
		(pin "T4"
		)
		(pin "L18"
		)
		(pin "E19"
		)
		(pin "H2"
		)
		(pin "L1"
		)
		(pin "F20"
		)
		(pin "B23"
		)
		(pin "R8"
		)
		(pin "M22"
		)
		(pin "F2"
		)
		(pin "E18"
		)
		(pin "R2"
		)
		(pin "W4"
		)
		(pin "B5"
		)
		(pin "W19"
		)
		(pin "N22"
		)
		(pin "D5"
		)
		(pin "W20"
		)
		(pin "W12"
		)
		(pin "B11"
		)
		(pin "R11"
		)
		(pin "E2"
		)
		(pin "D18"
		)
		(pin "T8"
		)
		(pin "L5"
		)
		(pin "M4"
		)
		(pin "T20"
		)
		(pin "A3"
		)
		(pin "AC3"
		)
		(pin "A19"
		)
		(pin "L16"
		)
		(pin "F4"
		)
		(pin "T12"
		)
		(pin "Y18"
		)
		(pin "T16"
		)
		(pin "AB19"
		)
		(pin "B12"
		)
		(pin "E23"
		)
		(pin "E1"
		)
		(pin "T6"
		)
		(pin "Y19"
		)
		(pin "T15"
		)
		(pin "P22"
		)
		(pin "AB16"
		)
		(pin "AC4"
		)
		(pin "D15"
		)
		(pin "G1"
		)
		(pin "A8"
		)
		(pin "Y12"
		)
		(pin "J4"
		)
		(pin "J1"
		)
		(pin "E22"
		)
		(pin "D20"
		)
		(pin "M2"
		)
		(pin "V23"
		)
		(pin "AB10"
		)
		(pin "AB2"
		)
		(pin "AC15"
		)
		(pin "D23"
		)
		(pin "A23"
		)
		(pin "C23"
		)
		(pin "J2"
		)
		(pin "A21"
		)
		(pin "F1"
		)
		(pin "H5"
		)
		(pin "N11"
		)
		(pin "B20"
		)
		(pin "H22"
		)
		(pin "AA23"
		)
		(pin "E13"
		)
		(pin "J12"
		)
		(pin "W9"
		)
		(pin "H9"
		)
		(pin "B19"
		)
		(pin "AB8"
		)
		(pin "AB22"
		)
		(pin "AB6"
		)
		(pin "AB20"
		)
		(pin "AC2"
		)
		(pin "E9"
		)
		(pin "J11"
		)
		(pin "L4"
		)
		(pin "J8"
		)
		(pin "AC22"
		)
		(pin "J13"
		)
		(pin "N12"
		)
		(pin "J15"
		)
		(pin "B18"
		)
		(pin "Y15"
		)
		(pin "U2"
		)
		(pin "AC12"
		)
		(pin "D16"
		)
		(pin "AB14"
		)
		(pin "AC6"
		)
		(pin "A14"
		)
		(pin "V13"
		)
		(pin "G22"
		)
		(pin "Y13"
		)
		(pin "B16"
		)
		(pin "AB18"
		)
		(pin "B17"
		)
		(pin "A20"
		)
		(pin "AB12"
		)
		(pin "R1"
		)
		(pin "AC20"
		)
		(pin "H12"
		)
		(pin "A2"
		)
		(pin "F5"
		)
		(pin "E6"
		)
		(pin "A10"
		)
		(pin "A12"
		)
		(pin "H11"
		)
		(pin "F9"
		)
		(pin "A1"
		)
		(pin "AB1"
		)
		(pin "E8"
		)
		(pin "A11"
		)
		(pin "L6"
		)
		(pin "B21"
		)
		(pin "AB23"
		)
		(pin "W13"
		)
		(pin "P2"
		)
		(pin "W16"
		)
		(pin "AC16"
		)
		(pin "H6"
		)
		(pin "Y6"
		)
		(pin "A15"
		)
		(pin "J6"
		)
		(pin "V16"
		)
		(pin "N9"
		)
		(pin "AC21"
		)
		(pin "J19"
		)
		(pin "J20"
		)
		(pin "AC17"
		)
		(pin "AC19"
		)
		(pin "M11"
		)
		(pin "D4"
		)
		(pin "P1"
		)
		(pin "W5"
		)
		(pin "R18"
		)
		(pin "E16"
		)
		(pin "N23"
		)
		(pin "A22"
		)
		(pin "R9"
		)
		(pin "D8"
		)
		(pin "E15"
		)
		(pin "M19"
		)
		(pin "Y20"
		)
		(pin "T9"
		)
		(pin "H13"
		)
		(pin "W15"
		)
		(pin "B10"
		)
		(pin "AC14"
		)
		(pin "AC18"
		)
		(pin "C2"
		)
		(pin "E5"
		)
		(pin "J22"
		)
		(pin "J18"
		)
		(pin "J16"
		)
		(pin "AC8"
		)
		(pin "B1"
		)
		(pin "N2"
		)
		(pin "E11"
		)
		(pin "A18"
		)
		(pin "H1"
		)
		(pin "G23"
		)
		(pin "A16"
		)
		(pin "D11"
		)
		(pin "B15"
		)
		(pin "F8"
		)
		(pin "E12"
		)
		(pin "AA22"
		)
		(pin "D12"
		)
		(pin "F6"
		)
		(instances
			(project "thunderbolt-gpu-adapter"
				(path ""
					(reference "U4")
					(unit 3)
				)
			)
		)
	)
	(symbol
		(lib_id "antmicroResistors0402:R_10k_0402")
		(at 35.56 281.94 0)
		(unit 1)
		(exclude_from_sim no)
		(in_bom yes)
		(on_board yes)
		(dnp no)
		(property "Reference" "R64"
			(at 41.91 280.67 0)
			(effects
				(font
					(size 1.27 1.27)
					(thickness 0.15)
				)
			)
		)
		(property "Value" "R_10k_0402"
			(at 55.88 294.64 0)
			(effects
				(font
					(size 1.27 1.27)
					(thickness 0.15)
				)
				(justify left bottom)
				(hide yes)
			)
		)
		(property "Footprint" "antmicro-footprints:R_0402_1005Metric"
			(at 55.88 297.18 0)
			(effects
				(font
					(size 1.27 1.27)
					(thickness 0.15)
				)
				(justify left bottom)
				(hide yes)
			)
		)
		(property "Datasheet" "https://www.bourns.com/docs/product-datasheets/cr.pdf"
			(at 55.88 299.72 0)
			(effects
				(font
					(size 1.27 1.27)
					(thickness 0.15)
				)
				(justify left bottom)
				(hide yes)
			)
		)
		(property "Description" ""
			(at 35.56 281.94 0)
			(effects
				(font
					(size 1.27 1.27)
				)
				(hide yes)
			)
		)
		(property "MPN" "CR0402-FX-1002GLF"
			(at 55.88 302.26 0)
			(effects
				(font
					(size 1.27 1.27)
					(thickness 0.15)
				)
				(justify left bottom)
				(hide yes)
			)
		)
		(property "Manufacturer" "Bourns"
			(at 55.88 304.8 0)
			(effects
				(font
					(size 1.27 1.27)
					(thickness 0.15)
				)
				(justify left bottom)
				(hide yes)
			)
		)
		(property "License" "Apache-2.0"
			(at 55.88 307.34 0)
			(effects
				(font
					(size 1.27 1.27)
					(thickness 0.15)
				)
				(justify left bottom)
				(hide yes)
			)
		)
		(property "Val" "10k"
			(at 38.1 281.94 0)
			(effects
				(font
					(size 1.27 1.27)
					(thickness 0.15)
				)
			)
		)
		(property "Tolerance" "1%"
			(at 55.88 292.1 0)
			(effects
				(font
					(size 1.27 1.27)
				)
				(justify left bottom)
				(hide yes)
			)
		)
		(property "Author" "Antmicro"
			(at 55.88 309.88 0)
			(effects
				(font
					(size 1.27 1.27)
					(thickness 0.15)
				)
				(justify left bottom)
				(hide yes)
			)
		)
		(pin "1"
		)
		(pin "2"
		)
		(instances
			(project "thunderbolt-gpu-adapter"
				(path ""
					(reference "R64")
					(unit 1)
				)
			)
		)
	)
	(symbol
		(lib_id "antmicroResistors0402:R_1M_0402")
		(at 182.88 214.63 0)
		(unit 1)
		(exclude_from_sim no)
		(in_bom yes)
		(on_board yes)
		(dnp no)
		(property "Reference" "R82"
			(at 181.61 213.36 0)
			(effects
				(font
					(size 1.27 1.27)
					(thickness 0.15)
				)
			)
		)
		(property "Value" "R_1M_0402"
			(at 203.2 227.33 0)
			(effects
				(font
					(size 1.27 1.27)
					(thickness 0.15)
				)
				(justify left bottom)
				(hide yes)
			)
		)
		(property "Footprint" "antmicro-footprints:R_0402_1005Metric"
			(at 203.2 229.87 0)
			(effects
				(font
					(size 1.27 1.27)
					(thickness 0.15)
				)
				(justify left bottom)
				(hide yes)
			)
		)
		(property "Datasheet" "https://www.bourns.com/docs/product-datasheets/cr.pdf"
			(at 203.2 232.41 0)
			(effects
				(font
					(size 1.27 1.27)
					(thickness 0.15)
				)
				(justify left bottom)
				(hide yes)
			)
		)
		(property "Description" ""
			(at 182.88 214.63 0)
			(effects
				(font
					(size 1.27 1.27)
				)
				(hide yes)
			)
		)
		(property "MPN" "CR0402-FX-1004GLF"
			(at 203.2 234.95 0)
			(effects
				(font
					(size 1.27 1.27)
					(thickness 0.15)
				)
				(justify left bottom)
				(hide yes)
			)
		)
		(property "Manufacturer" "Bourns"
			(at 203.2 237.49 0)
			(effects
				(font
					(size 1.27 1.27)
					(thickness 0.15)
				)
				(justify left bottom)
				(hide yes)
			)
		)
		(property "License" "Apache-2.0"
			(at 203.2 240.03 0)
			(effects
				(font
					(size 1.27 1.27)
					(thickness 0.15)
				)
				(justify left bottom)
				(hide yes)
			)
		)
		(property "Val" "1M"
			(at 189.23 213.36 0)
			(effects
				(font
					(size 1.27 1.27)
					(thickness 0.15)
				)
			)
		)
		(property "Tolerance" "1%"
			(at 203.2 224.79 0)
			(effects
				(font
					(size 1.27 1.27)
				)
				(justify left bottom)
				(hide yes)
			)
		)
		(property "Author" "Antmicro"
			(at 203.2 242.57 0)
			(effects
				(font
					(size 1.27 1.27)
					(thickness 0.15)
				)
				(justify left bottom)
				(hide yes)
			)
		)
		(pin "1"
		)
		(pin "2"
		)
		(instances
			(project "thunderbolt-gpu-adapter"
				(path ""
					(reference "R82")
					(unit 1)
				)
			)
		)
	)
	(symbol
		(lib_id "antmicropower:GND")
		(at 194.31 215.9 0)
		(unit 1)
		(exclude_from_sim no)
		(in_bom yes)
		(on_board yes)
		(dnp no)
		(property "Reference" "#PWR0143"
			(at 194.31 222.25 0)
			(effects
				(font
					(size 1.27 1.27)
				)
				(hide yes)
			)
		)
		(property "Value" "GND"
			(at 194.31 219.71 0)
			(effects
				(font
					(size 1.27 1.27)
				)
			)
		)
		(property "Footprint" ""
			(at 194.31 215.9 0)
			(effects
				(font
					(size 1.27 1.27)
				)
				(hide yes)
			)
		)
		(property "Datasheet" ""
			(at 194.31 215.9 0)
			(effects
				(font
					(size 1.27 1.27)
				)
				(hide yes)
			)
		)
		(property "Description" ""
			(at 194.31 215.9 0)
			(effects
				(font
					(size 1.27 1.27)
				)
				(hide yes)
			)
		)
		(property "Author" "Antmicro"
			(at 203.2 223.52 0)
			(effects
				(font
					(size 1.27 1.27)
					(thickness 0.15)
				)
				(justify left bottom)
				(hide yes)
			)
		)
		(property "License" "Apache-2.0"
			(at 203.2 226.06 0)
			(effects
				(font
					(size 1.27 1.27)
					(thickness 0.15)
				)
				(justify left bottom)
				(hide yes)
			)
		)
		(pin "1"
		)
		(instances
			(project "thunderbolt-gpu-adapter"
				(path ""
					(reference "#PWR0143")
					(unit 1)
				)
			)
		)
	)
	(symbol
		(lib_id "antmicroCapacitors0402:C_220n_0402")
		(at 243.84 83.82 0)
		(unit 1)
		(exclude_from_sim no)
		(in_bom yes)
		(on_board yes)
		(dnp no)
		(property "Reference" "C108"
			(at 242.57 82.55 0)
			(effects
				(font
					(size 1.27 1.27)
					(thickness 0.15)
				)
			)
		)
		(property "Value" "C_220n_0402"
			(at 264.16 93.98 0)
			(effects
				(font
					(size 1.27 1.27)
					(thickness 0.15)
				)
				(justify left bottom)
				(hide yes)
			)
		)
		(property "Footprint" "antmicro-footprints:C_0402_1005Metric"
			(at 264.16 96.52 0)
			(effects
				(font
					(size 1.27 1.27)
					(thickness 0.15)
				)
				(justify left bottom)
				(hide yes)
			)
		)
		(property "Datasheet" "https://www.yageo.com/en/Chart/Download/pdf/CC0402KRX5R6BB224"
			(at 264.16 99.06 0)
			(effects
				(font
					(size 1.27 1.27)
					(thickness 0.15)
				)
				(justify left bottom)
				(hide yes)
			)
		)
		(property "Description" ""
			(at 243.84 83.82 0)
			(effects
				(font
					(size 1.27 1.27)
				)
				(hide yes)
			)
		)
		(property "MPN" "CC0402KRX5R6BB224"
			(at 264.16 101.6 0)
			(effects
				(font
					(size 1.27 1.27)
					(thickness 0.15)
				)
				(justify left bottom)
				(hide yes)
			)
		)
		(property "Manufacturer" "YAGEO"
			(at 264.16 104.14 0)
			(effects
				(font
					(size 1.27 1.27)
					(thickness 0.15)
				)
				(justify left bottom)
				(hide yes)
			)
		)
		(property "License" "Apache-2.0"
			(at 264.16 106.68 0)
			(effects
				(font
					(size 1.27 1.27)
					(thickness 0.15)
				)
				(justify left bottom)
				(hide yes)
			)
		)
		(property "Val" "220n"
			(at 242.57 85.09 0)
			(effects
				(font
					(size 1.27 1.27)
					(thickness 0.15)
				)
			)
		)
		(property "Voltage" ""
			(at 264.16 111.76 0)
			(effects
				(font
					(size 1.27 1.27)
				)
				(justify left bottom)
				(hide yes)
			)
		)
		(property "Dielectric" ""
			(at 264.16 114.3 0)
			(effects
				(font
					(size 1.27 1.27)
				)
				(justify left bottom)
				(hide yes)
			)
		)
		(property "Author" "Antmicro"
			(at 264.16 109.22 0)
			(effects
				(font
					(size 1.27 1.27)
					(thickness 0.15)
				)
				(justify left bottom)
				(hide yes)
			)
		)
		(pin "1"
		)
		(pin "2"
		)
		(instances
			(project "thunderbolt-gpu-adapter"
				(path ""
					(reference "C108")
					(unit 1)
				)
			)
		)
	)
	(symbol
		(lib_id "antmicroCapacitors0402:C_220n_0402")
		(at 243.84 76.2 0)
		(unit 1)
		(exclude_from_sim no)
		(in_bom yes)
		(on_board yes)
		(dnp no)
		(property "Reference" "C107"
			(at 242.57 74.93 0)
			(effects
				(font
					(size 1.27 1.27)
					(thickness 0.15)
				)
			)
		)
		(property "Value" "C_220n_0402"
			(at 264.16 86.36 0)
			(effects
				(font
					(size 1.27 1.27)
					(thickness 0.15)
				)
				(justify left bottom)
				(hide yes)
			)
		)
		(property "Footprint" "antmicro-footprints:C_0402_1005Metric"
			(at 264.16 88.9 0)
			(effects
				(font
					(size 1.27 1.27)
					(thickness 0.15)
				)
				(justify left bottom)
				(hide yes)
			)
		)
		(property "Datasheet" "https://www.yageo.com/en/Chart/Download/pdf/CC0402KRX5R6BB224"
			(at 264.16 91.44 0)
			(effects
				(font
					(size 1.27 1.27)
					(thickness 0.15)
				)
				(justify left bottom)
				(hide yes)
			)
		)
		(property "Description" ""
			(at 243.84 76.2 0)
			(effects
				(font
					(size 1.27 1.27)
				)
				(hide yes)
			)
		)
		(property "MPN" "CC0402KRX5R6BB224"
			(at 264.16 93.98 0)
			(effects
				(font
					(size 1.27 1.27)
					(thickness 0.15)
				)
				(justify left bottom)
				(hide yes)
			)
		)
		(property "Manufacturer" "YAGEO"
			(at 264.16 96.52 0)
			(effects
				(font
					(size 1.27 1.27)
					(thickness 0.15)
				)
				(justify left bottom)
				(hide yes)
			)
		)
		(property "License" "Apache-2.0"
			(at 264.16 99.06 0)
			(effects
				(font
					(size 1.27 1.27)
					(thickness 0.15)
				)
				(justify left bottom)
				(hide yes)
			)
		)
		(property "Val" "220n"
			(at 242.57 77.47 0)
			(effects
				(font
					(size 1.27 1.27)
					(thickness 0.15)
				)
			)
		)
		(property "Voltage" ""
			(at 264.16 104.14 0)
			(effects
				(font
					(size 1.27 1.27)
				)
				(justify left bottom)
				(hide yes)
			)
		)
		(property "Dielectric" ""
			(at 264.16 106.68 0)
			(effects
				(font
					(size 1.27 1.27)
				)
				(justify left bottom)
				(hide yes)
			)
		)
		(property "Author" "Antmicro"
			(at 264.16 101.6 0)
			(effects
				(font
					(size 1.27 1.27)
					(thickness 0.15)
				)
				(justify left bottom)
				(hide yes)
			)
		)
		(pin "1"
		)
		(pin "2"
		)
		(instances
			(project "thunderbolt-gpu-adapter"
				(path ""
					(reference "C107")
					(unit 1)
				)
			)
		)
	)
	(symbol
		(lib_id "antmicroCapacitors0402:C_220n_0402")
		(at 250.19 73.66 0)
		(unit 1)
		(exclude_from_sim no)
		(in_bom yes)
		(on_board yes)
		(dnp no)
		(property "Reference" "C111"
			(at 256.54 72.39 0)
			(effects
				(font
					(size 1.27 1.27)
					(thickness 0.15)
				)
			)
		)
		(property "Value" "C_220n_0402"
			(at 270.51 83.82 0)
			(effects
				(font
					(size 1.27 1.27)
					(thickness 0.15)
				)
				(justify left bottom)
				(hide yes)
			)
		)
		(property "Footprint" "antmicro-footprints:C_0402_1005Metric"
			(at 270.51 86.36 0)
			(effects
				(font
					(size 1.27 1.27)
					(thickness 0.15)
				)
				(justify left bottom)
				(hide yes)
			)
		)
		(property "Datasheet" "https://www.yageo.com/en/Chart/Download/pdf/CC0402KRX5R6BB224"
			(at 270.51 88.9 0)
			(effects
				(font
					(size 1.27 1.27)
					(thickness 0.15)
				)
				(justify left bottom)
				(hide yes)
			)
		)
		(property "Description" ""
			(at 250.19 73.66 0)
			(effects
				(font
					(size 1.27 1.27)
				)
				(hide yes)
			)
		)
		(property "MPN" "CC0402KRX5R6BB224"
			(at 270.51 91.44 0)
			(effects
				(font
					(size 1.27 1.27)
					(thickness 0.15)
				)
				(justify left bottom)
				(hide yes)
			)
		)
		(property "Manufacturer" "YAGEO"
			(at 270.51 93.98 0)
			(effects
				(font
					(size 1.27 1.27)
					(thickness 0.15)
				)
				(justify left bottom)
				(hide yes)
			)
		)
		(property "License" "Apache-2.0"
			(at 270.51 96.52 0)
			(effects
				(font
					(size 1.27 1.27)
					(thickness 0.15)
				)
				(justify left bottom)
				(hide yes)
			)
		)
		(property "Val" "220n"
			(at 256.54 74.93 0)
			(effects
				(font
					(size 1.27 1.27)
					(thickness 0.15)
				)
			)
		)
		(property "Voltage" ""
			(at 270.51 101.6 0)
			(effects
				(font
					(size 1.27 1.27)
				)
				(justify left bottom)
				(hide yes)
			)
		)
		(property "Dielectric" ""
			(at 270.51 104.14 0)
			(effects
				(font
					(size 1.27 1.27)
				)
				(justify left bottom)
				(hide yes)
			)
		)
		(property "Author" "Antmicro"
			(at 270.51 99.06 0)
			(effects
				(font
					(size 1.27 1.27)
					(thickness 0.15)
				)
				(justify left bottom)
				(hide yes)
			)
		)
		(pin "1"
		)
		(pin "2"
		)
		(instances
			(project "thunderbolt-gpu-adapter"
				(path ""
					(reference "C111")
					(unit 1)
				)
			)
		)
	)
	(symbol
		(lib_id "antmicropower:GND")
		(at 191.77 361.95 270)
		(unit 1)
		(exclude_from_sim no)
		(in_bom yes)
		(on_board yes)
		(dnp no)
		(property "Reference" "#PWR0141"
			(at 185.42 361.95 0)
			(effects
				(font
					(size 1.27 1.27)
				)
				(hide yes)
			)
		)
		(property "Value" "GND"
			(at 187.96 361.95 0)
			(effects
				(font
					(size 1.27 1.27)
				)
			)
		)
		(property "Footprint" ""
			(at 191.77 361.95 0)
			(effects
				(font
					(size 1.27 1.27)
				)
				(hide yes)
			)
		)
		(property "Datasheet" ""
			(at 191.77 361.95 0)
			(effects
				(font
					(size 1.27 1.27)
				)
				(hide yes)
			)
		)
		(property "Description" ""
			(at 191.77 361.95 0)
			(effects
				(font
					(size 1.27 1.27)
				)
				(hide yes)
			)
		)
		(property "Author" "Antmicro"
			(at 184.15 370.84 0)
			(effects
				(font
					(size 1.27 1.27)
					(thickness 0.15)
				)
				(justify left bottom)
				(hide yes)
			)
		)
		(property "License" "Apache-2.0"
			(at 181.61 370.84 0)
			(effects
				(font
					(size 1.27 1.27)
					(thickness 0.15)
				)
				(justify left bottom)
				(hide yes)
			)
		)
		(pin "1"
		)
		(instances
			(project "thunderbolt-gpu-adapter"
				(path ""
					(reference "#PWR0141")
					(unit 1)
				)
			)
		)
	)
	(symbol
		(lib_id "antmicropower:GND")
		(at 220.98 368.3 0)
		(unit 1)
		(exclude_from_sim no)
		(in_bom yes)
		(on_board yes)
		(dnp no)
		(property "Reference" "#PWR0148"
			(at 220.98 374.65 0)
			(effects
				(font
					(size 1.27 1.27)
				)
				(hide yes)
			)
		)
		(property "Value" "GND"
			(at 220.98 372.11 0)
			(effects
				(font
					(size 1.27 1.27)
				)
			)
		)
		(property "Footprint" ""
			(at 220.98 368.3 0)
			(effects
				(font
					(size 1.27 1.27)
				)
				(hide yes)
			)
		)
		(property "Datasheet" ""
			(at 220.98 368.3 0)
			(effects
				(font
					(size 1.27 1.27)
				)
				(hide yes)
			)
		)
		(property "Description" ""
			(at 220.98 368.3 0)
			(effects
				(font
					(size 1.27 1.27)
				)
				(hide yes)
			)
		)
		(property "Author" "Antmicro"
			(at 229.87 375.92 0)
			(effects
				(font
					(size 1.27 1.27)
					(thickness 0.15)
				)
				(justify left bottom)
				(hide yes)
			)
		)
		(property "License" "Apache-2.0"
			(at 229.87 378.46 0)
			(effects
				(font
					(size 1.27 1.27)
					(thickness 0.15)
				)
				(justify left bottom)
				(hide yes)
			)
		)
		(pin "1"
		)
		(instances
			(project "thunderbolt-gpu-adapter"
				(path ""
					(reference "#PWR0148")
					(unit 1)
				)
			)
		)
	)
	(symbol
		(lib_id "antmicroResistors0402:R_100k_0402")
		(at 182.88 201.93 0)
		(unit 1)
		(exclude_from_sim no)
		(in_bom yes)
		(on_board yes)
		(dnp no)
		(property "Reference" "R77"
			(at 181.61 200.66 0)
			(effects
				(font
					(size 1.27 1.27)
					(thickness 0.15)
				)
			)
		)
		(property "Value" "R_100k_0402"
			(at 203.2 214.63 0)
			(effects
				(font
					(size 1.27 1.27)
					(thickness 0.15)
				)
				(justify left bottom)
				(hide yes)
			)
		)
		(property "Footprint" "antmicro-footprints:R_0402_1005Metric"
			(at 203.2 217.17 0)
			(effects
				(font
					(size 1.27 1.27)
					(thickness 0.15)
				)
				(justify left bottom)
				(hide yes)
			)
		)
		(property "Datasheet" "https://www.bourns.com/docs/product-datasheets/cr.pdf"
			(at 203.2 219.71 0)
			(effects
				(font
					(size 1.27 1.27)
					(thickness 0.15)
				)
				(justify left bottom)
				(hide yes)
			)
		)
		(property "Description" ""
			(at 182.88 201.93 0)
			(effects
				(font
					(size 1.27 1.27)
				)
				(hide yes)
			)
		)
		(property "MPN" "CR0402-FX-1003GLF"
			(at 203.2 222.25 0)
			(effects
				(font
					(size 1.27 1.27)
					(thickness 0.15)
				)
				(justify left bottom)
				(hide yes)
			)
		)
		(property "Manufacturer" "Bourns"
			(at 203.2 224.79 0)
			(effects
				(font
					(size 1.27 1.27)
					(thickness 0.15)
				)
				(justify left bottom)
				(hide yes)
			)
		)
		(property "License" "Apache-2.0"
			(at 203.2 227.33 0)
			(effects
				(font
					(size 1.27 1.27)
					(thickness 0.15)
				)
				(justify left bottom)
				(hide yes)
			)
		)
		(property "Val" "100k"
			(at 189.865 200.66 0)
			(effects
				(font
					(size 1.27 1.27)
					(thickness 0.15)
				)
			)
		)
		(property "Tolerance" "1%"
			(at 203.2 212.09 0)
			(effects
				(font
					(size 1.27 1.27)
				)
				(justify left bottom)
				(hide yes)
			)
		)
		(property "Author" "Antmicro"
			(at 203.2 229.87 0)
			(effects
				(font
					(size 1.27 1.27)
					(thickness 0.15)
				)
				(justify left bottom)
				(hide yes)
			)
		)
		(pin "1"
		)
		(pin "2"
		)
		(instances
			(project "thunderbolt-gpu-adapter"
				(path ""
					(reference "R77")
					(unit 1)
				)
			)
		)
	)
	(symbol
		(lib_id "antmicroInterfaceControllers:JHL6340SLLSQ")
		(at 71.12 48.26 0)
		(unit 5)
		(exclude_from_sim no)
		(in_bom yes)
		(on_board yes)
		(dnp no)
		(fields_autoplaced yes)
		(property "Reference" "U4"
			(at 99.06 40.005 0)
			(effects
				(font
					(size 1.27 1.27)
					(thickness 0.15)
				)
			)
		)
		(property "Value" "JHL6340SLLSQ"
			(at 142.24 50.8 0)
			(effects
				(font
					(size 1.27 1.27)
					(thickness 0.15)
				)
				(justify left bottom)
				(hide yes)
			)
		)
		(property "Footprint" "antmicro-footprints:JHL6340SLLSQ"
			(at 142.24 53.34 0)
			(effects
				(font
					(size 1.27 1.27)
					(thickness 0.15)
				)
				(justify left bottom)
				(hide yes)
			)
		)
		(property "Datasheet" "https://www.thunderbolttechnology.net/sites/default/files/18-241_ThunderboltController_Brief_HI.pdf"
			(at 142.24 55.88 0)
			(effects
				(font
					(size 1.27 1.27)
					(thickness 0.15)
				)
				(justify left bottom)
				(hide yes)
			)
		)
		(property "Description" ""
			(at 71.12 48.26 0)
			(effects
				(font
					(size 1.27 1.27)
				)
				(hide yes)
			)
		)
		(property "Manufacturer" "Intel"
			(at 142.24 58.42 0)
			(effects
				(font
					(size 1.27 1.27)
					(thickness 0.15)
				)
				(justify left bottom)
				(hide yes)
			)
		)
		(property "MPN" "JHL6340SLLSQ"
			(at 99.06 42.545 0)
			(effects
				(font
					(size 1.27 1.27)
					(thickness 0.15)
				)
			)
		)
		(property "Author" "Antmicro"
			(at 142.24 63.5 0)
			(effects
				(font
					(size 1.27 1.27)
					(thickness 0.15)
				)
				(justify left bottom)
				(hide yes)
			)
		)
		(property "License" "Apache-2.0"
			(at 142.24 66.04 0)
			(effects
				(font
					(size 1.27 1.27)
					(thickness 0.15)
				)
				(justify left bottom)
				(hide yes)
			)
		)
		(pin "V5"
		)
		(pin "Y9"
		)
		(pin "AC5"
		)
		(pin "F12"
		)
		(pin "L13"
		)
		(pin "A13"
		)
		(pin "T23"
		)
		(pin "AA2"
		)
		(pin "L22"
		)
		(pin "R16"
		)
		(pin "N13"
		)
		(pin "D9"
		)
		(pin "T2"
		)
		(pin "R12"
		)
		(pin "U1"
		)
		(pin "R23"
		)
		(pin "J23"
		)
		(pin "T22"
		)
		(pin "L23"
		)
		(pin "B3"
		)
		(pin "V4"
		)
		(pin "N8"
		)
		(pin "AB11"
		)
		(pin "AB4"
		)
		(pin "M6"
		)
		(pin "K22"
		)
		(pin "R5"
		)
		(pin "L15"
		)
		(pin "F13"
		)
		(pin "L12"
		)
		(pin "H20"
		)
		(pin "V15"
		)
		(pin "V22"
		)
		(pin "V19"
		)
		(pin "P23"
		)
		(pin "M18"
		)
		(pin "A4"
		)
		(pin "A9"
		)
		(pin "M23"
		)
		(pin "Y8"
		)
		(pin "Y4"
		)
		(pin "N5"
		)
		(pin "T5"
		)
		(pin "W1"
		)
		(pin "Y11"
		)
		(pin "Y5"
		)
		(pin "B22"
		)
		(pin "B6"
		)
		(pin "V8"
		)
		(pin "V1"
		)
		(pin "A17"
		)
		(pin "Y2"
		)
		(pin "W2"
		)
		(pin "R22"
		)
		(pin "N6"
		)
		(pin "F16"
		)
		(pin "AB13"
		)
		(pin "H4"
		)
		(pin "F22"
		)
		(pin "R4"
		)
		(pin "F23"
		)
		(pin "W11"
		)
		(pin "D13"
		)
		(pin "AC10"
		)
		(pin "M9"
		)
		(pin "V2"
		)
		(pin "L19"
		)
		(pin "T18"
		)
		(pin "L20"
		)
		(pin "H8"
		)
		(pin "AB7"
		)
		(pin "Y23"
		)
		(pin "K1"
		)
		(pin "AC7"
		)
		(pin "H18"
		)
		(pin "C1"
		)
		(pin "N1"
		)
		(pin "AB5"
		)
		(pin "J5"
		)
		(pin "R15"
		)
		(pin "M13"
		)
		(pin "D1"
		)
		(pin "E20"
		)
		(pin "AC11"
		)
		(pin "A5"
		)
		(pin "AB15"
		)
		(pin "L8"
		)
		(pin "D6"
		)
		(pin "D19"
		)
		(pin "V6"
		)
		(pin "N19"
		)
		(pin "T11"
		)
		(pin "W8"
		)
		(pin "C22"
		)
		(pin "H19"
		)
		(pin "L11"
		)
		(pin "AC13"
		)
		(pin "D2"
		)
		(pin "K23"
		)
		(pin "L2"
		)
		(pin "A7"
		)
		(pin "H16"
		)
		(pin "Y16"
		)
		(pin "V12"
		)
		(pin "AB9"
		)
		(pin "M20"
		)
		(pin "N20"
		)
		(pin "R19"
		)
		(pin "U22"
		)
		(pin "AB21"
		)
		(pin "E4"
		)
		(pin "R6"
		)
		(pin "R20"
		)
		(pin "AC1"
		)
		(pin "G2"
		)
		(pin "M8"
		)
		(pin "M16"
		)
		(pin "V20"
		)
		(pin "F18"
		)
		(pin "AB3"
		)
		(pin "AA1"
		)
		(pin "D22"
		)
		(pin "V11"
		)
		(pin "T1"
		)
		(pin "V18"
		)
		(pin "B9"
		)
		(pin "J9"
		)
		(pin "M5"
		)
		(pin "H15"
		)
		(pin "M12"
		)
		(pin "M15"
		)
		(pin "AC9"
		)
		(pin "W23"
		)
		(pin "V9"
		)
		(pin "B8"
		)
		(pin "N16"
		)
		(pin "B14"
		)
		(pin "AC23"
		)
		(pin "W18"
		)
		(pin "M1"
		)
		(pin "N15"
		)
		(pin "AB17"
		)
		(pin "U23"
		)
		(pin "Y22"
		)
		(pin "L9"
		)
		(pin "T13"
		)
		(pin "F11"
		)
		(pin "N4"
		)
		(pin "F19"
		)
		(pin "W6"
		)
		(pin "F15"
		)
		(pin "B7"
		)
		(pin "Y1"
		)
		(pin "A6"
		)
		(pin "B2"
		)
		(pin "B4"
		)
		(pin "R13"
		)
		(pin "K2"
		)
		(pin "N18"
		)
		(pin "B13"
		)
		(pin "T19"
		)
		(pin "W22"
		)
		(pin "H23"
		)
		(pin "T4"
		)
		(pin "L18"
		)
		(pin "E19"
		)
		(pin "H2"
		)
		(pin "L1"
		)
		(pin "F20"
		)
		(pin "B23"
		)
		(pin "R8"
		)
		(pin "M22"
		)
		(pin "F2"
		)
		(pin "E18"
		)
		(pin "R2"
		)
		(pin "W4"
		)
		(pin "B5"
		)
		(pin "W19"
		)
		(pin "N22"
		)
		(pin "D5"
		)
		(pin "W20"
		)
		(pin "W12"
		)
		(pin "B11"
		)
		(pin "R11"
		)
		(pin "E2"
		)
		(pin "D18"
		)
		(pin "T8"
		)
		(pin "L5"
		)
		(pin "M4"
		)
		(pin "T20"
		)
		(pin "A3"
		)
		(pin "AC3"
		)
		(pin "A19"
		)
		(pin "L16"
		)
		(pin "F4"
		)
		(pin "T12"
		)
		(pin "Y18"
		)
		(pin "T16"
		)
		(pin "AB19"
		)
		(pin "B12"
		)
		(pin "E23"
		)
		(pin "E1"
		)
		(pin "T6"
		)
		(pin "Y19"
		)
		(pin "T15"
		)
		(pin "P22"
		)
		(pin "AB16"
		)
		(pin "AC4"
		)
		(pin "D15"
		)
		(pin "G1"
		)
		(pin "A8"
		)
		(pin "Y12"
		)
		(pin "J4"
		)
		(pin "J1"
		)
		(pin "E22"
		)
		(pin "D20"
		)
		(pin "M2"
		)
		(pin "V23"
		)
		(pin "AB10"
		)
		(pin "AB2"
		)
		(pin "AC15"
		)
		(pin "D23"
		)
		(pin "A23"
		)
		(pin "C23"
		)
		(pin "J2"
		)
		(pin "A21"
		)
		(pin "F1"
		)
		(pin "H5"
		)
		(pin "N11"
		)
		(pin "B20"
		)
		(pin "H22"
		)
		(pin "AA23"
		)
		(pin "E13"
		)
		(pin "J12"
		)
		(pin "W9"
		)
		(pin "H9"
		)
		(pin "B19"
		)
		(pin "AB8"
		)
		(pin "AB22"
		)
		(pin "AB6"
		)
		(pin "AB20"
		)
		(pin "AC2"
		)
		(pin "E9"
		)
		(pin "J11"
		)
		(pin "L4"
		)
		(pin "J8"
		)
		(pin "AC22"
		)
		(pin "J13"
		)
		(pin "N12"
		)
		(pin "J15"
		)
		(pin "B18"
		)
		(pin "Y15"
		)
		(pin "U2"
		)
		(pin "AC12"
		)
		(pin "D16"
		)
		(pin "AB14"
		)
		(pin "AC6"
		)
		(pin "A14"
		)
		(pin "V13"
		)
		(pin "G22"
		)
		(pin "Y13"
		)
		(pin "B16"
		)
		(pin "AB18"
		)
		(pin "B17"
		)
		(pin "A20"
		)
		(pin "AB12"
		)
		(pin "R1"
		)
		(pin "AC20"
		)
		(pin "H12"
		)
		(pin "A2"
		)
		(pin "F5"
		)
		(pin "E6"
		)
		(pin "A10"
		)
		(pin "A12"
		)
		(pin "H11"
		)
		(pin "F9"
		)
		(pin "A1"
		)
		(pin "AB1"
		)
		(pin "E8"
		)
		(pin "A11"
		)
		(pin "L6"
		)
		(pin "B21"
		)
		(pin "AB23"
		)
		(pin "W13"
		)
		(pin "P2"
		)
		(pin "W16"
		)
		(pin "AC16"
		)
		(pin "H6"
		)
		(pin "Y6"
		)
		(pin "A15"
		)
		(pin "J6"
		)
		(pin "V16"
		)
		(pin "N9"
		)
		(pin "AC21"
		)
		(pin "J19"
		)
		(pin "J20"
		)
		(pin "AC17"
		)
		(pin "AC19"
		)
		(pin "M11"
		)
		(pin "D4"
		)
		(pin "P1"
		)
		(pin "W5"
		)
		(pin "R18"
		)
		(pin "E16"
		)
		(pin "N23"
		)
		(pin "A22"
		)
		(pin "R9"
		)
		(pin "D8"
		)
		(pin "E15"
		)
		(pin "M19"
		)
		(pin "Y20"
		)
		(pin "T9"
		)
		(pin "H13"
		)
		(pin "W15"
		)
		(pin "B10"
		)
		(pin "AC14"
		)
		(pin "AC18"
		)
		(pin "C2"
		)
		(pin "E5"
		)
		(pin "J22"
		)
		(pin "J18"
		)
		(pin "J16"
		)
		(pin "AC8"
		)
		(pin "B1"
		)
		(pin "N2"
		)
		(pin "E11"
		)
		(pin "A18"
		)
		(pin "H1"
		)
		(pin "G23"
		)
		(pin "A16"
		)
		(pin "D11"
		)
		(pin "B15"
		)
		(pin "F8"
		)
		(pin "E12"
		)
		(pin "AA22"
		)
		(pin "D12"
		)
		(pin "F6"
		)
		(instances
			(project "thunderbolt-gpu-adapter"
				(path ""
					(reference "U4")
					(unit 5)
				)
			)
		)
	)
	(symbol
		(lib_id "antmicropower:GND")
		(at 39.37 360.68 0)
		(unit 1)
		(exclude_from_sim no)
		(in_bom yes)
		(on_board yes)
		(dnp no)
		(property "Reference" "#PWR0129"
			(at 39.37 367.03 0)
			(effects
				(font
					(size 1.27 1.27)
				)
				(hide yes)
			)
		)
		(property "Value" "GND"
			(at 39.37 364.49 0)
			(effects
				(font
					(size 1.27 1.27)
				)
			)
		)
		(property "Footprint" ""
			(at 39.37 360.68 0)
			(effects
				(font
					(size 1.27 1.27)
				)
				(hide yes)
			)
		)
		(property "Datasheet" ""
			(at 39.37 360.68 0)
			(effects
				(font
					(size 1.27 1.27)
				)
				(hide yes)
			)
		)
		(property "Description" ""
			(at 39.37 360.68 0)
			(effects
				(font
					(size 1.27 1.27)
				)
				(hide yes)
			)
		)
		(property "Author" "Antmicro"
			(at 48.26 368.3 0)
			(effects
				(font
					(size 1.27 1.27)
					(thickness 0.15)
				)
				(justify left bottom)
				(hide yes)
			)
		)
		(property "License" "Apache-2.0"
			(at 48.26 370.84 0)
			(effects
				(font
					(size 1.27 1.27)
					(thickness 0.15)
				)
				(justify left bottom)
				(hide yes)
			)
		)
		(pin "1"
		)
		(instances
			(project "thunderbolt-gpu-adapter"
				(path ""
					(reference "#PWR0129")
					(unit 1)
				)
			)
		)
	)
	(symbol
		(lib_id "antmicroResistors0402:R_100k_0402")
		(at 182.88 181.61 0)
		(unit 1)
		(exclude_from_sim no)
		(in_bom yes)
		(on_board yes)
		(dnp no)
		(fields_autoplaced yes)
		(property "Reference" "R75"
			(at 185.42 175.26 0)
			(effects
				(font
					(size 1.27 1.27)
					(thickness 0.15)
				)
			)
		)
		(property "Value" "R_100k_0402"
			(at 203.2 194.31 0)
			(effects
				(font
					(size 1.27 1.27)
					(thickness 0.15)
				)
				(justify left bottom)
				(hide yes)
			)
		)
		(property "Footprint" "antmicro-footprints:R_0402_1005Metric"
			(at 203.2 196.85 0)
			(effects
				(font
					(size 1.27 1.27)
					(thickness 0.15)
				)
				(justify left bottom)
				(hide yes)
			)
		)
		(property "Datasheet" "https://www.bourns.com/docs/product-datasheets/cr.pdf"
			(at 203.2 199.39 0)
			(effects
				(font
					(size 1.27 1.27)
					(thickness 0.15)
				)
				(justify left bottom)
				(hide yes)
			)
		)
		(property "Description" ""
			(at 182.88 181.61 0)
			(effects
				(font
					(size 1.27 1.27)
				)
				(hide yes)
			)
		)
		(property "MPN" "CR0402-FX-1003GLF"
			(at 203.2 201.93 0)
			(effects
				(font
					(size 1.27 1.27)
					(thickness 0.15)
				)
				(justify left bottom)
				(hide yes)
			)
		)
		(property "Manufacturer" "Bourns"
			(at 203.2 204.47 0)
			(effects
				(font
					(size 1.27 1.27)
					(thickness 0.15)
				)
				(justify left bottom)
				(hide yes)
			)
		)
		(property "License" "Apache-2.0"
			(at 203.2 207.01 0)
			(effects
				(font
					(size 1.27 1.27)
					(thickness 0.15)
				)
				(justify left bottom)
				(hide yes)
			)
		)
		(property "Val" "100k"
			(at 185.42 177.8 0)
			(effects
				(font
					(size 1.27 1.27)
					(thickness 0.15)
				)
			)
		)
		(property "Tolerance" "1%"
			(at 203.2 191.77 0)
			(effects
				(font
					(size 1.27 1.27)
				)
				(justify left bottom)
				(hide yes)
			)
		)
		(property "Author" "Antmicro"
			(at 203.2 209.55 0)
			(effects
				(font
					(size 1.27 1.27)
					(thickness 0.15)
				)
				(justify left bottom)
				(hide yes)
			)
		)
		(pin "1"
		)
		(pin "2"
		)
		(instances
			(project "thunderbolt-gpu-adapter"
				(path ""
					(reference "R75")
					(unit 1)
				)
			)
		)
	)
	(symbol
		(lib_id "antmicroResistors0402:R_10k_0402")
		(at 165.1 96.52 0)
		(unit 1)
		(exclude_from_sim no)
		(in_bom yes)
		(on_board yes)
		(dnp no)
		(fields_autoplaced yes)
		(property "Reference" "R56"
			(at 167.64 100.33 0)
			(effects
				(font
					(size 1.27 1.27)
					(thickness 0.15)
				)
			)
		)
		(property "Value" "R_10k_0402"
			(at 185.42 109.22 0)
			(effects
				(font
					(size 1.27 1.27)
					(thickness 0.15)
				)
				(justify left bottom)
				(hide yes)
			)
		)
		(property "Footprint" "antmicro-footprints:R_0402_1005Metric"
			(at 185.42 111.76 0)
			(effects
				(font
					(size 1.27 1.27)
					(thickness 0.15)
				)
				(justify left bottom)
				(hide yes)
			)
		)
		(property "Datasheet" "https://www.bourns.com/docs/product-datasheets/cr.pdf"
			(at 185.42 114.3 0)
			(effects
				(font
					(size 1.27 1.27)
					(thickness 0.15)
				)
				(justify left bottom)
				(hide yes)
			)
		)
		(property "Description" ""
			(at 165.1 96.52 0)
			(effects
				(font
					(size 1.27 1.27)
				)
				(hide yes)
			)
		)
		(property "MPN" "CR0402-FX-1002GLF"
			(at 185.42 116.84 0)
			(effects
				(font
					(size 1.27 1.27)
					(thickness 0.15)
				)
				(justify left bottom)
				(hide yes)
			)
		)
		(property "Manufacturer" "Bourns"
			(at 185.42 119.38 0)
			(effects
				(font
					(size 1.27 1.27)
					(thickness 0.15)
				)
				(justify left bottom)
				(hide yes)
			)
		)
		(property "License" "Apache-2.0"
			(at 185.42 121.92 0)
			(effects
				(font
					(size 1.27 1.27)
					(thickness 0.15)
				)
				(justify left bottom)
				(hide yes)
			)
		)
		(property "Val" "10k"
			(at 167.64 102.87 0)
			(effects
				(font
					(size 1.27 1.27)
					(thickness 0.15)
				)
			)
		)
		(property "Tolerance" "1%"
			(at 185.42 106.68 0)
			(effects
				(font
					(size 1.27 1.27)
				)
				(justify left bottom)
				(hide yes)
			)
		)
		(property "Author" "Antmicro"
			(at 185.42 124.46 0)
			(effects
				(font
					(size 1.27 1.27)
					(thickness 0.15)
				)
				(justify left bottom)
				(hide yes)
			)
		)
		(pin "1"
		)
		(pin "2"
		)
		(instances
			(project "thunderbolt-gpu-adapter"
				(path ""
					(reference "R56")
					(unit 1)
				)
			)
		)
	)
	(symbol
		(lib_id "antmicroResistors0402:R_100k_0402")
		(at 114.3 234.95 0)
		(unit 1)
		(exclude_from_sim no)
		(in_bom yes)
		(on_board yes)
		(dnp no)
		(fields_autoplaced yes)
		(property "Reference" "R60"
			(at 116.84 228.6 0)
			(effects
				(font
					(size 1.27 1.27)
					(thickness 0.15)
				)
			)
		)
		(property "Value" "R_100k_0402"
			(at 134.62 247.65 0)
			(effects
				(font
					(size 1.27 1.27)
					(thickness 0.15)
				)
				(justify left bottom)
				(hide yes)
			)
		)
		(property "Footprint" "antmicro-footprints:R_0402_1005Metric"
			(at 134.62 250.19 0)
			(effects
				(font
					(size 1.27 1.27)
					(thickness 0.15)
				)
				(justify left bottom)
				(hide yes)
			)
		)
		(property "Datasheet" "https://www.bourns.com/docs/product-datasheets/cr.pdf"
			(at 134.62 252.73 0)
			(effects
				(font
					(size 1.27 1.27)
					(thickness 0.15)
				)
				(justify left bottom)
				(hide yes)
			)
		)
		(property "Description" ""
			(at 114.3 234.95 0)
			(effects
				(font
					(size 1.27 1.27)
				)
				(hide yes)
			)
		)
		(property "MPN" "CR0402-FX-1003GLF"
			(at 134.62 255.27 0)
			(effects
				(font
					(size 1.27 1.27)
					(thickness 0.15)
				)
				(justify left bottom)
				(hide yes)
			)
		)
		(property "Manufacturer" "Bourns"
			(at 134.62 257.81 0)
			(effects
				(font
					(size 1.27 1.27)
					(thickness 0.15)
				)
				(justify left bottom)
				(hide yes)
			)
		)
		(property "License" "Apache-2.0"
			(at 134.62 260.35 0)
			(effects
				(font
					(size 1.27 1.27)
					(thickness 0.15)
				)
				(justify left bottom)
				(hide yes)
			)
		)
		(property "Val" "100k"
			(at 116.84 231.14 0)
			(effects
				(font
					(size 1.27 1.27)
					(thickness 0.15)
				)
			)
		)
		(property "Tolerance" "1%"
			(at 134.62 245.11 0)
			(effects
				(font
					(size 1.27 1.27)
				)
				(justify left bottom)
				(hide yes)
			)
		)
		(property "Author" "Antmicro"
			(at 134.62 262.89 0)
			(effects
				(font
					(size 1.27 1.27)
					(thickness 0.15)
				)
				(justify left bottom)
				(hide yes)
			)
		)
		(pin "1"
		)
		(pin "2"
		)
		(instances
			(project "thunderbolt-gpu-adapter"
				(path ""
					(reference "R60")
					(unit 1)
				)
			)
		)
	)
	(symbol
		(lib_id "antmicroCapacitors0402:C_100n_0402")
		(at 215.9 353.06 90)
		(unit 1)
		(exclude_from_sim no)
		(in_bom yes)
		(on_board yes)
		(dnp no)
		(fields_autoplaced yes)
		(property "Reference" "C115"
			(at 212.725 349.2436 90)
			(effects
				(font
					(size 1.27 1.27)
					(thickness 0.15)
				)
				(justify left)
			)
		)
		(property "Value" "C_100n_0402"
			(at 226.06 332.74 0)
			(effects
				(font
					(size 1.27 1.27)
					(thickness 0.15)
				)
				(justify left bottom)
				(hide yes)
			)
		)
		(property "Footprint" "antmicro-footprints:C_0402_1005Metric"
			(at 228.6 332.74 0)
			(effects
				(font
					(size 1.27 1.27)
					(thickness 0.15)
				)
				(justify left bottom)
				(hide yes)
			)
		)
		(property "Datasheet" "https://www.murata.com/products/productdetail?partno=GRM155R61H104KE14%23"
			(at 231.14 332.74 0)
			(effects
				(font
					(size 1.27 1.27)
					(thickness 0.15)
				)
				(justify left bottom)
				(hide yes)
			)
		)
		(property "Description" ""
			(at 215.9 353.06 0)
			(effects
				(font
					(size 1.27 1.27)
				)
				(hide yes)
			)
		)
		(property "MPN" "GRM155R61H104KE14D"
			(at 233.68 332.74 0)
			(effects
				(font
					(size 1.27 1.27)
					(thickness 0.15)
				)
				(justify left bottom)
				(hide yes)
			)
		)
		(property "Manufacturer" "Murata"
			(at 236.22 332.74 0)
			(effects
				(font
					(size 1.27 1.27)
					(thickness 0.15)
				)
				(justify left bottom)
				(hide yes)
			)
		)
		(property "License" "Apache-2.0"
			(at 238.76 332.74 0)
			(effects
				(font
					(size 1.27 1.27)
					(thickness 0.15)
				)
				(justify left bottom)
				(hide yes)
			)
		)
		(property "Val" "100n"
			(at 212.725 351.7836 90)
			(effects
				(font
					(size 1.27 1.27)
					(thickness 0.15)
				)
				(justify left)
			)
		)
		(property "Voltage" "50V"
			(at 243.84 332.74 0)
			(effects
				(font
					(size 1.27 1.27)
				)
				(justify left bottom)
				(hide yes)
			)
		)
		(property "Dielectric" "X5R"
			(at 246.38 332.74 0)
			(effects
				(font
					(size 1.27 1.27)
				)
				(justify left bottom)
				(hide yes)
			)
		)
		(property "Author" "Antmicro"
			(at 241.3 332.74 0)
			(effects
				(font
					(size 1.27 1.27)
					(thickness 0.15)
				)
				(justify left bottom)
				(hide yes)
			)
		)
		(pin "1"
		)
		(pin "2"
		)
		(instances
			(project "thunderbolt-gpu-adapter"
				(path ""
					(reference "C115")
					(unit 1)
				)
			)
		)
	)
	(symbol
		(lib_id "antmicroResistors0402:R_100k_0402")
		(at 182.88 234.95 0)
		(unit 1)
		(exclude_from_sim no)
		(in_bom yes)
		(on_board yes)
		(dnp no)
		(property "Reference" "R86"
			(at 181.61 233.68 0)
			(effects
				(font
					(size 1.27 1.27)
					(thickness 0.15)
				)
			)
		)
		(property "Value" "R_100k_0402"
			(at 203.2 247.65 0)
			(effects
				(font
					(size 1.27 1.27)
					(thickness 0.15)
				)
				(justify left bottom)
				(hide yes)
			)
		)
		(property "Footprint" "antmicro-footprints:R_0402_1005Metric"
			(at 203.2 250.19 0)
			(effects
				(font
					(size 1.27 1.27)
					(thickness 0.15)
				)
				(justify left bottom)
				(hide yes)
			)
		)
		(property "Datasheet" "https://www.bourns.com/docs/product-datasheets/cr.pdf"
			(at 203.2 252.73 0)
			(effects
				(font
					(size 1.27 1.27)
					(thickness 0.15)
				)
				(justify left bottom)
				(hide yes)
			)
		)
		(property "Description" ""
			(at 182.88 234.95 0)
			(effects
				(font
					(size 1.27 1.27)
				)
				(hide yes)
			)
		)
		(property "MPN" "CR0402-FX-1003GLF"
			(at 203.2 255.27 0)
			(effects
				(font
					(size 1.27 1.27)
					(thickness 0.15)
				)
				(justify left bottom)
				(hide yes)
			)
		)
		(property "Manufacturer" "Bourns"
			(at 203.2 257.81 0)
			(effects
				(font
					(size 1.27 1.27)
					(thickness 0.15)
				)
				(justify left bottom)
				(hide yes)
			)
		)
		(property "License" "Apache-2.0"
			(at 203.2 260.35 0)
			(effects
				(font
					(size 1.27 1.27)
					(thickness 0.15)
				)
				(justify left bottom)
				(hide yes)
			)
		)
		(property "Val" "100k"
			(at 189.865 233.68 0)
			(effects
				(font
					(size 1.27 1.27)
					(thickness 0.15)
				)
			)
		)
		(property "Tolerance" "1%"
			(at 203.2 245.11 0)
			(effects
				(font
					(size 1.27 1.27)
				)
				(justify left bottom)
				(hide yes)
			)
		)
		(property "Author" "Antmicro"
			(at 203.2 262.89 0)
			(effects
				(font
					(size 1.27 1.27)
					(thickness 0.15)
				)
				(justify left bottom)
				(hide yes)
			)
		)
		(pin "1"
		)
		(pin "2"
		)
		(instances
			(project "thunderbolt-gpu-adapter"
				(path ""
					(reference "R86")
					(unit 1)
				)
			)
		)
	)
	(symbol
		(lib_id "antmicroResistors0402:R_100R_0402")
		(at 104.14 284.48 0)
		(unit 1)
		(exclude_from_sim no)
		(in_bom yes)
		(on_board yes)
		(dnp no)
		(property "Reference" "R89"
			(at 102.87 283.21 0)
			(effects
				(font
					(size 1.27 1.27)
					(thickness 0.15)
				)
			)
		)
		(property "Value" "R_100R_0402"
			(at 124.46 297.18 0)
			(effects
				(font
					(size 1.27 1.27)
					(thickness 0.15)
				)
				(justify left bottom)
				(hide yes)
			)
		)
		(property "Footprint" "antmicro-footprints:R_0402_1005Metric"
			(at 124.46 299.72 0)
			(effects
				(font
					(size 1.27 1.27)
					(thickness 0.15)
				)
				(justify left bottom)
				(hide yes)
			)
		)
		(property "Datasheet" "https://www.bourns.com/docs/product-datasheets/cr.pdf"
			(at 124.46 302.26 0)
			(effects
				(font
					(size 1.27 1.27)
					(thickness 0.15)
				)
				(justify left bottom)
				(hide yes)
			)
		)
		(property "Description" ""
			(at 104.14 284.48 0)
			(effects
				(font
					(size 1.27 1.27)
				)
				(hide yes)
			)
		)
		(property "MPN" "CR0402-FX-1000GLF"
			(at 124.46 304.8 0)
			(effects
				(font
					(size 1.27 1.27)
					(thickness 0.15)
				)
				(justify left bottom)
				(hide yes)
			)
		)
		(property "Manufacturer" "Bourns"
			(at 124.46 307.34 0)
			(effects
				(font
					(size 1.27 1.27)
					(thickness 0.15)
				)
				(justify left bottom)
				(hide yes)
			)
		)
		(property "License" "Apache-2.0"
			(at 124.46 309.88 0)
			(effects
				(font
					(size 1.27 1.27)
					(thickness 0.15)
				)
				(justify left bottom)
				(hide yes)
			)
		)
		(property "Val" "100R"
			(at 111.125 283.21 0)
			(effects
				(font
					(size 1.27 1.27)
					(thickness 0.15)
				)
			)
		)
		(property "Tolerance" "1%"
			(at 124.46 294.64 0)
			(effects
				(font
					(size 1.27 1.27)
				)
				(justify left bottom)
				(hide yes)
			)
		)
		(property "Author" "Antmicro"
			(at 124.46 312.42 0)
			(effects
				(font
					(size 1.27 1.27)
					(thickness 0.15)
				)
				(justify left bottom)
				(hide yes)
			)
		)
		(pin "1"
		)
		(pin "2"
		)
		(instances
			(project "thunderbolt-gpu-adapter"
				(path ""
					(reference "R89")
					(unit 1)
				)
			)
		)
	)
	(symbol
		(lib_id "antmicropower:GND")
		(at 187.96 368.3 270)
		(unit 1)
		(exclude_from_sim no)
		(in_bom yes)
		(on_board yes)
		(dnp no)
		(property "Reference" "#PWR0138"
			(at 181.61 368.3 0)
			(effects
				(font
					(size 1.27 1.27)
				)
				(hide yes)
			)
		)
		(property "Value" "GND"
			(at 184.15 368.3 0)
			(effects
				(font
					(size 1.27 1.27)
				)
			)
		)
		(property "Footprint" ""
			(at 187.96 368.3 0)
			(effects
				(font
					(size 1.27 1.27)
				)
				(hide yes)
			)
		)
		(property "Datasheet" ""
			(at 187.96 368.3 0)
			(effects
				(font
					(size 1.27 1.27)
				)
				(hide yes)
			)
		)
		(property "Description" ""
			(at 187.96 368.3 0)
			(effects
				(font
					(size 1.27 1.27)
				)
				(hide yes)
			)
		)
		(property "Author" "Antmicro"
			(at 180.34 377.19 0)
			(effects
				(font
					(size 1.27 1.27)
					(thickness 0.15)
				)
				(justify left bottom)
				(hide yes)
			)
		)
		(property "License" "Apache-2.0"
			(at 177.8 377.19 0)
			(effects
				(font
					(size 1.27 1.27)
					(thickness 0.15)
				)
				(justify left bottom)
				(hide yes)
			)
		)
		(pin "1"
		)
		(instances
			(project "thunderbolt-gpu-adapter"
				(path ""
					(reference "#PWR0138")
					(unit 1)
				)
			)
		)
	)
	(symbol
		(lib_id "antmicroCapacitors0402:C_220n_0402")
		(at 250.19 66.04 0)
		(unit 1)
		(exclude_from_sim no)
		(in_bom yes)
		(on_board yes)
		(dnp no)
		(property "Reference" "C110"
			(at 256.54 64.77 0)
			(effects
				(font
					(size 1.27 1.27)
					(thickness 0.15)
				)
			)
		)
		(property "Value" "C_220n_0402"
			(at 270.51 76.2 0)
			(effects
				(font
					(size 1.27 1.27)
					(thickness 0.15)
				)
				(justify left bottom)
				(hide yes)
			)
		)
		(property "Footprint" "antmicro-footprints:C_0402_1005Metric"
			(at 270.51 78.74 0)
			(effects
				(font
					(size 1.27 1.27)
					(thickness 0.15)
				)
				(justify left bottom)
				(hide yes)
			)
		)
		(property "Datasheet" "https://www.yageo.com/en/Chart/Download/pdf/CC0402KRX5R6BB224"
			(at 270.51 81.28 0)
			(effects
				(font
					(size 1.27 1.27)
					(thickness 0.15)
				)
				(justify left bottom)
				(hide yes)
			)
		)
		(property "Description" ""
			(at 250.19 66.04 0)
			(effects
				(font
					(size 1.27 1.27)
				)
				(hide yes)
			)
		)
		(property "MPN" "CC0402KRX5R6BB224"
			(at 270.51 83.82 0)
			(effects
				(font
					(size 1.27 1.27)
					(thickness 0.15)
				)
				(justify left bottom)
				(hide yes)
			)
		)
		(property "Manufacturer" "YAGEO"
			(at 270.51 86.36 0)
			(effects
				(font
					(size 1.27 1.27)
					(thickness 0.15)
				)
				(justify left bottom)
				(hide yes)
			)
		)
		(property "License" "Apache-2.0"
			(at 270.51 88.9 0)
			(effects
				(font
					(size 1.27 1.27)
					(thickness 0.15)
				)
				(justify left bottom)
				(hide yes)
			)
		)
		(property "Val" "220n"
			(at 256.54 67.31 0)
			(effects
				(font
					(size 1.27 1.27)
					(thickness 0.15)
				)
			)
		)
		(property "Voltage" ""
			(at 270.51 93.98 0)
			(effects
				(font
					(size 1.27 1.27)
				)
				(justify left bottom)
				(hide yes)
			)
		)
		(property "Dielectric" ""
			(at 270.51 96.52 0)
			(effects
				(font
					(size 1.27 1.27)
				)
				(justify left bottom)
				(hide yes)
			)
		)
		(property "Author" "Antmicro"
			(at 270.51 91.44 0)
			(effects
				(font
					(size 1.27 1.27)
					(thickness 0.15)
				)
				(justify left bottom)
				(hide yes)
			)
		)
		(pin "1"
		)
		(pin "2"
		)
		(instances
			(project "thunderbolt-gpu-adapter"
				(path ""
					(reference "C110")
					(unit 1)
				)
			)
		)
	)
	(symbol
		(lib_id "antmicropower:GND")
		(at 149.86 288.29 90)
		(unit 1)
		(exclude_from_sim no)
		(in_bom yes)
		(on_board yes)
		(dnp no)
		(property "Reference" "#PWR0150"
			(at 156.21 288.29 0)
			(effects
				(font
					(size 1.27 1.27)
				)
				(hide yes)
			)
		)
		(property "Value" "GND"
			(at 153.67 288.29 0)
			(effects
				(font
					(size 1.27 1.27)
				)
			)
		)
		(property "Footprint" ""
			(at 149.86 288.29 0)
			(effects
				(font
					(size 1.27 1.27)
				)
				(hide yes)
			)
		)
		(property "Datasheet" ""
			(at 149.86 288.29 0)
			(effects
				(font
					(size 1.27 1.27)
				)
				(hide yes)
			)
		)
		(property "Description" ""
			(at 149.86 288.29 0)
			(effects
				(font
					(size 1.27 1.27)
				)
				(hide yes)
			)
		)
		(property "Author" "Antmicro"
			(at 157.48 279.4 0)
			(effects
				(font
					(size 1.27 1.27)
					(thickness 0.15)
				)
				(justify left bottom)
				(hide yes)
			)
		)
		(property "License" "Apache-2.0"
			(at 160.02 279.4 0)
			(effects
				(font
					(size 1.27 1.27)
					(thickness 0.15)
				)
				(justify left bottom)
				(hide yes)
			)
		)
		(pin "1"
		)
		(instances
			(project "thunderbolt-gpu-adapter"
				(path ""
					(reference "#PWR0150")
					(unit 1)
				)
			)
		)
	)
	(symbol
		(lib_id "antmicroInterfaceControllers:JHL6340SLLSQ")
		(at 185.42 280.67 0)
		(unit 6)
		(exclude_from_sim no)
		(in_bom yes)
		(on_board yes)
		(dnp no)
		(fields_autoplaced yes)
		(property "Reference" "U4"
			(at 213.36 273.05 0)
			(effects
				(font
					(size 1.27 1.27)
					(thickness 0.15)
				)
			)
		)
		(property "Value" "JHL6340SLLSQ"
			(at 256.54 283.21 0)
			(effects
				(font
					(size 1.27 1.27)
					(thickness 0.15)
				)
				(justify left bottom)
				(hide yes)
			)
		)
		(property "Footprint" "antmicro-footprints:JHL6340SLLSQ"
			(at 256.54 285.75 0)
			(effects
				(font
					(size 1.27 1.27)
					(thickness 0.15)
				)
				(justify left bottom)
				(hide yes)
			)
		)
		(property "Datasheet" "https://www.thunderbolttechnology.net/sites/default/files/18-241_ThunderboltController_Brief_HI.pdf"
			(at 256.54 288.29 0)
			(effects
				(font
					(size 1.27 1.27)
					(thickness 0.15)
				)
				(justify left bottom)
				(hide yes)
			)
		)
		(property "Description" ""
			(at 185.42 280.67 0)
			(effects
				(font
					(size 1.27 1.27)
				)
				(hide yes)
			)
		)
		(property "Manufacturer" "Intel"
			(at 256.54 290.83 0)
			(effects
				(font
					(size 1.27 1.27)
					(thickness 0.15)
				)
				(justify left bottom)
				(hide yes)
			)
		)
		(property "MPN" "JHL6340SLLSQ"
			(at 213.36 275.59 0)
			(effects
				(font
					(size 1.27 1.27)
					(thickness 0.15)
				)
			)
		)
		(property "Author" "Antmicro"
			(at 256.54 295.91 0)
			(effects
				(font
					(size 1.27 1.27)
					(thickness 0.15)
				)
				(justify left bottom)
				(hide yes)
			)
		)
		(property "License" "Apache-2.0"
			(at 256.54 298.45 0)
			(effects
				(font
					(size 1.27 1.27)
					(thickness 0.15)
				)
				(justify left bottom)
				(hide yes)
			)
		)
		(pin "V5"
		)
		(pin "Y9"
		)
		(pin "AC5"
		)
		(pin "F12"
		)
		(pin "L13"
		)
		(pin "A13"
		)
		(pin "T23"
		)
		(pin "AA2"
		)
		(pin "L22"
		)
		(pin "R16"
		)
		(pin "N13"
		)
		(pin "D9"
		)
		(pin "T2"
		)
		(pin "R12"
		)
		(pin "U1"
		)
		(pin "R23"
		)
		(pin "J23"
		)
		(pin "T22"
		)
		(pin "L23"
		)
		(pin "B3"
		)
		(pin "V4"
		)
		(pin "N8"
		)
		(pin "AB11"
		)
		(pin "AB4"
		)
		(pin "M6"
		)
		(pin "K22"
		)
		(pin "R5"
		)
		(pin "L15"
		)
		(pin "F13"
		)
		(pin "L12"
		)
		(pin "H20"
		)
		(pin "V15"
		)
		(pin "V22"
		)
		(pin "V19"
		)
		(pin "P23"
		)
		(pin "M18"
		)
		(pin "A4"
		)
		(pin "A9"
		)
		(pin "M23"
		)
		(pin "Y8"
		)
		(pin "Y4"
		)
		(pin "N5"
		)
		(pin "T5"
		)
		(pin "W1"
		)
		(pin "Y11"
		)
		(pin "Y5"
		)
		(pin "B22"
		)
		(pin "B6"
		)
		(pin "V8"
		)
		(pin "V1"
		)
		(pin "A17"
		)
		(pin "Y2"
		)
		(pin "W2"
		)
		(pin "R22"
		)
		(pin "N6"
		)
		(pin "F16"
		)
		(pin "AB13"
		)
		(pin "H4"
		)
		(pin "F22"
		)
		(pin "R4"
		)
		(pin "F23"
		)
		(pin "W11"
		)
		(pin "D13"
		)
		(pin "AC10"
		)
		(pin "M9"
		)
		(pin "V2"
		)
		(pin "L19"
		)
		(pin "T18"
		)
		(pin "L20"
		)
		(pin "H8"
		)
		(pin "AB7"
		)
		(pin "Y23"
		)
		(pin "K1"
		)
		(pin "AC7"
		)
		(pin "H18"
		)
		(pin "C1"
		)
		(pin "N1"
		)
		(pin "AB5"
		)
		(pin "J5"
		)
		(pin "R15"
		)
		(pin "M13"
		)
		(pin "D1"
		)
		(pin "E20"
		)
		(pin "AC11"
		)
		(pin "A5"
		)
		(pin "AB15"
		)
		(pin "L8"
		)
		(pin "D6"
		)
		(pin "D19"
		)
		(pin "V6"
		)
		(pin "N19"
		)
		(pin "T11"
		)
		(pin "W8"
		)
		(pin "C22"
		)
		(pin "H19"
		)
		(pin "L11"
		)
		(pin "AC13"
		)
		(pin "D2"
		)
		(pin "K23"
		)
		(pin "L2"
		)
		(pin "A7"
		)
		(pin "H16"
		)
		(pin "Y16"
		)
		(pin "V12"
		)
		(pin "AB9"
		)
		(pin "M20"
		)
		(pin "N20"
		)
		(pin "R19"
		)
		(pin "U22"
		)
		(pin "AB21"
		)
		(pin "E4"
		)
		(pin "R6"
		)
		(pin "R20"
		)
		(pin "AC1"
		)
		(pin "G2"
		)
		(pin "M8"
		)
		(pin "M16"
		)
		(pin "V20"
		)
		(pin "F18"
		)
		(pin "AB3"
		)
		(pin "AA1"
		)
		(pin "D22"
		)
		(pin "V11"
		)
		(pin "T1"
		)
		(pin "V18"
		)
		(pin "B9"
		)
		(pin "J9"
		)
		(pin "M5"
		)
		(pin "H15"
		)
		(pin "M12"
		)
		(pin "M15"
		)
		(pin "AC9"
		)
		(pin "W23"
		)
		(pin "V9"
		)
		(pin "B8"
		)
		(pin "N16"
		)
		(pin "B14"
		)
		(pin "AC23"
		)
		(pin "W18"
		)
		(pin "M1"
		)
		(pin "N15"
		)
		(pin "AB17"
		)
		(pin "U23"
		)
		(pin "Y22"
		)
		(pin "L9"
		)
		(pin "T13"
		)
		(pin "F11"
		)
		(pin "N4"
		)
		(pin "F19"
		)
		(pin "W6"
		)
		(pin "F15"
		)
		(pin "B7"
		)
		(pin "Y1"
		)
		(pin "A6"
		)
		(pin "B2"
		)
		(pin "B4"
		)
		(pin "R13"
		)
		(pin "K2"
		)
		(pin "N18"
		)
		(pin "B13"
		)
		(pin "T19"
		)
		(pin "W22"
		)
		(pin "H23"
		)
		(pin "T4"
		)
		(pin "L18"
		)
		(pin "E19"
		)
		(pin "H2"
		)
		(pin "L1"
		)
		(pin "F20"
		)
		(pin "B23"
		)
		(pin "R8"
		)
		(pin "M22"
		)
		(pin "F2"
		)
		(pin "E18"
		)
		(pin "R2"
		)
		(pin "W4"
		)
		(pin "B5"
		)
		(pin "W19"
		)
		(pin "N22"
		)
		(pin "D5"
		)
		(pin "W20"
		)
		(pin "W12"
		)
		(pin "B11"
		)
		(pin "R11"
		)
		(pin "E2"
		)
		(pin "D18"
		)
		(pin "T8"
		)
		(pin "L5"
		)
		(pin "M4"
		)
		(pin "T20"
		)
		(pin "A3"
		)
		(pin "AC3"
		)
		(pin "A19"
		)
		(pin "L16"
		)
		(pin "F4"
		)
		(pin "T12"
		)
		(pin "Y18"
		)
		(pin "T16"
		)
		(pin "AB19"
		)
		(pin "B12"
		)
		(pin "E23"
		)
		(pin "E1"
		)
		(pin "T6"
		)
		(pin "Y19"
		)
		(pin "T15"
		)
		(pin "P22"
		)
		(pin "AB16"
		)
		(pin "AC4"
		)
		(pin "D15"
		)
		(pin "G1"
		)
		(pin "A8"
		)
		(pin "Y12"
		)
		(pin "J4"
		)
		(pin "J1"
		)
		(pin "E22"
		)
		(pin "D20"
		)
		(pin "M2"
		)
		(pin "V23"
		)
		(pin "AB10"
		)
		(pin "AB2"
		)
		(pin "AC15"
		)
		(pin "D23"
		)
		(pin "A23"
		)
		(pin "C23"
		)
		(pin "J2"
		)
		(pin "A21"
		)
		(pin "F1"
		)
		(pin "H5"
		)
		(pin "N11"
		)
		(pin "B20"
		)
		(pin "H22"
		)
		(pin "AA23"
		)
		(pin "E13"
		)
		(pin "J12"
		)
		(pin "W9"
		)
		(pin "H9"
		)
		(pin "B19"
		)
		(pin "AB8"
		)
		(pin "AB22"
		)
		(pin "AB6"
		)
		(pin "AB20"
		)
		(pin "AC2"
		)
		(pin "E9"
		)
		(pin "J11"
		)
		(pin "L4"
		)
		(pin "J8"
		)
		(pin "AC22"
		)
		(pin "J13"
		)
		(pin "N12"
		)
		(pin "J15"
		)
		(pin "B18"
		)
		(pin "Y15"
		)
		(pin "U2"
		)
		(pin "AC12"
		)
		(pin "D16"
		)
		(pin "AB14"
		)
		(pin "AC6"
		)
		(pin "A14"
		)
		(pin "V13"
		)
		(pin "G22"
		)
		(pin "Y13"
		)
		(pin "B16"
		)
		(pin "AB18"
		)
		(pin "B17"
		)
		(pin "A20"
		)
		(pin "AB12"
		)
		(pin "R1"
		)
		(pin "AC20"
		)
		(pin "H12"
		)
		(pin "A2"
		)
		(pin "F5"
		)
		(pin "E6"
		)
		(pin "A10"
		)
		(pin "A12"
		)
		(pin "H11"
		)
		(pin "F9"
		)
		(pin "A1"
		)
		(pin "AB1"
		)
		(pin "E8"
		)
		(pin "A11"
		)
		(pin "L6"
		)
		(pin "B21"
		)
		(pin "AB23"
		)
		(pin "W13"
		)
		(pin "P2"
		)
		(pin "W16"
		)
		(pin "AC16"
		)
		(pin "H6"
		)
		(pin "Y6"
		)
		(pin "A15"
		)
		(pin "J6"
		)
		(pin "V16"
		)
		(pin "N9"
		)
		(pin "AC21"
		)
		(pin "J19"
		)
		(pin "J20"
		)
		(pin "AC17"
		)
		(pin "AC19"
		)
		(pin "M11"
		)
		(pin "D4"
		)
		(pin "P1"
		)
		(pin "W5"
		)
		(pin "R18"
		)
		(pin "E16"
		)
		(pin "N23"
		)
		(pin "A22"
		)
		(pin "R9"
		)
		(pin "D8"
		)
		(pin "E15"
		)
		(pin "M19"
		)
		(pin "Y20"
		)
		(pin "T9"
		)
		(pin "H13"
		)
		(pin "W15"
		)
		(pin "B10"
		)
		(pin "AC14"
		)
		(pin "AC18"
		)
		(pin "C2"
		)
		(pin "E5"
		)
		(pin "J22"
		)
		(pin "J18"
		)
		(pin "J16"
		)
		(pin "AC8"
		)
		(pin "B1"
		)
		(pin "N2"
		)
		(pin "E11"
		)
		(pin "A18"
		)
		(pin "H1"
		)
		(pin "G23"
		)
		(pin "A16"
		)
		(pin "D11"
		)
		(pin "B15"
		)
		(pin "F8"
		)
		(pin "E12"
		)
		(pin "AA22"
		)
		(pin "D12"
		)
		(pin "F6"
		)
		(instances
			(project "thunderbolt-gpu-adapter"
				(path ""
					(reference "U4")
					(unit 6)
				)
			)
		)
	)
	(symbol
		(lib_id "antmicroResistors0402:R_100R_0402")
		(at 104.14 281.94 0)
		(unit 1)
		(exclude_from_sim no)
		(in_bom yes)
		(on_board yes)
		(dnp no)
		(property "Reference" "R88"
			(at 102.87 280.67 0)
			(effects
				(font
					(size 1.27 1.27)
					(thickness 0.15)
				)
			)
		)
		(property "Value" "R_100R_0402"
			(at 124.46 294.64 0)
			(effects
				(font
					(size 1.27 1.27)
					(thickness 0.15)
				)
				(justify left bottom)
				(hide yes)
			)
		)
		(property "Footprint" "antmicro-footprints:R_0402_1005Metric"
			(at 124.46 297.18 0)
			(effects
				(font
					(size 1.27 1.27)
					(thickness 0.15)
				)
				(justify left bottom)
				(hide yes)
			)
		)
		(property "Datasheet" "https://www.bourns.com/docs/product-datasheets/cr.pdf"
			(at 124.46 299.72 0)
			(effects
				(font
					(size 1.27 1.27)
					(thickness 0.15)
				)
				(justify left bottom)
				(hide yes)
			)
		)
		(property "Description" ""
			(at 104.14 281.94 0)
			(effects
				(font
					(size 1.27 1.27)
				)
				(hide yes)
			)
		)
		(property "MPN" "CR0402-FX-1000GLF"
			(at 124.46 302.26 0)
			(effects
				(font
					(size 1.27 1.27)
					(thickness 0.15)
				)
				(justify left bottom)
				(hide yes)
			)
		)
		(property "Manufacturer" "Bourns"
			(at 124.46 304.8 0)
			(effects
				(font
					(size 1.27 1.27)
					(thickness 0.15)
				)
				(justify left bottom)
				(hide yes)
			)
		)
		(property "License" "Apache-2.0"
			(at 124.46 307.34 0)
			(effects
				(font
					(size 1.27 1.27)
					(thickness 0.15)
				)
				(justify left bottom)
				(hide yes)
			)
		)
		(property "Val" "100R"
			(at 111.125 280.67 0)
			(effects
				(font
					(size 1.27 1.27)
					(thickness 0.15)
				)
			)
		)
		(property "Tolerance" "1%"
			(at 124.46 292.1 0)
			(effects
				(font
					(size 1.27 1.27)
				)
				(justify left bottom)
				(hide yes)
			)
		)
		(property "Author" "Antmicro"
			(at 124.46 309.88 0)
			(effects
				(font
					(size 1.27 1.27)
					(thickness 0.15)
				)
				(justify left bottom)
				(hide yes)
			)
		)
		(pin "1"
		)
		(pin "2"
		)
		(instances
			(project "thunderbolt-gpu-adapter"
				(path ""
					(reference "R88")
					(unit 1)
				)
			)
		)
	)
	(symbol
		(lib_id "antmicroCapacitors0402:C_220n_0402")
		(at 39.37 63.5 0)
		(unit 1)
		(exclude_from_sim no)
		(in_bom yes)
		(on_board yes)
		(dnp no)
		(fields_autoplaced yes)
		(property "Reference" "C99"
			(at 41.9163 57.15 0)
			(effects
				(font
					(size 1.27 1.27)
					(thickness 0.15)
				)
			)
		)
		(property "Value" "C_220n_0402"
			(at 59.69 73.66 0)
			(effects
				(font
					(size 1.27 1.27)
					(thickness 0.15)
				)
				(justify left bottom)
				(hide yes)
			)
		)
		(property "Footprint" "antmicro-footprints:C_0402_1005Metric"
			(at 59.69 76.2 0)
			(effects
				(font
					(size 1.27 1.27)
					(thickness 0.15)
				)
				(justify left bottom)
				(hide yes)
			)
		)
		(property "Datasheet" "https://www.yageo.com/en/Chart/Download/pdf/CC0402KRX5R6BB224"
			(at 59.69 78.74 0)
			(effects
				(font
					(size 1.27 1.27)
					(thickness 0.15)
				)
				(justify left bottom)
				(hide yes)
			)
		)
		(property "Description" ""
			(at 39.37 63.5 0)
			(effects
				(font
					(size 1.27 1.27)
				)
				(hide yes)
			)
		)
		(property "MPN" "CC0402KRX5R6BB224"
			(at 59.69 81.28 0)
			(effects
				(font
					(size 1.27 1.27)
					(thickness 0.15)
				)
				(justify left bottom)
				(hide yes)
			)
		)
		(property "Manufacturer" "YAGEO"
			(at 59.69 83.82 0)
			(effects
				(font
					(size 1.27 1.27)
					(thickness 0.15)
				)
				(justify left bottom)
				(hide yes)
			)
		)
		(property "License" "Apache-2.0"
			(at 59.69 86.36 0)
			(effects
				(font
					(size 1.27 1.27)
					(thickness 0.15)
				)
				(justify left bottom)
				(hide yes)
			)
		)
		(property "Author" "Antmicro"
			(at 59.69 88.9 0)
			(effects
				(font
					(size 1.27 1.27)
					(thickness 0.15)
				)
				(justify left bottom)
				(hide yes)
			)
		)
		(property "Val" "220n"
			(at 41.9163 59.69 0)
			(effects
				(font
					(size 1.27 1.27)
					(thickness 0.15)
				)
			)
		)
		(property "Voltage" ""
			(at 59.69 91.44 0)
			(effects
				(font
					(size 1.27 1.27)
				)
				(justify left bottom)
				(hide yes)
			)
		)
		(property "Dielectric" ""
			(at 59.69 93.98 0)
			(effects
				(font
					(size 1.27 1.27)
				)
				(justify left bottom)
				(hide yes)
			)
		)
		(pin "1"
		)
		(pin "2"
		)
		(instances
			(project "thunderbolt-gpu-adapter"
				(path ""
					(reference "C99")
					(unit 1)
				)
			)
		)
	)
	(symbol
		(lib_id "antmicropower:GND")
		(at 194.31 238.76 0)
		(unit 1)
		(exclude_from_sim no)
		(in_bom yes)
		(on_board yes)
		(dnp no)
		(property "Reference" "#PWR047"
			(at 194.31 245.11 0)
			(effects
				(font
					(size 1.27 1.27)
				)
				(hide yes)
			)
		)
		(property "Value" "GND"
			(at 194.31 242.57 0)
			(effects
				(font
					(size 1.27 1.27)
				)
			)
		)
		(property "Footprint" ""
			(at 194.31 238.76 0)
			(effects
				(font
					(size 1.27 1.27)
				)
				(hide yes)
			)
		)
		(property "Datasheet" ""
			(at 194.31 238.76 0)
			(effects
				(font
					(size 1.27 1.27)
				)
				(hide yes)
			)
		)
		(property "Description" ""
			(at 194.31 238.76 0)
			(effects
				(font
					(size 1.27 1.27)
				)
				(hide yes)
			)
		)
		(property "Author" "Antmicro"
			(at 203.2 246.38 0)
			(effects
				(font
					(size 1.27 1.27)
					(thickness 0.15)
				)
				(justify left bottom)
				(hide yes)
			)
		)
		(property "License" "Apache-2.0"
			(at 203.2 248.92 0)
			(effects
				(font
					(size 1.27 1.27)
					(thickness 0.15)
				)
				(justify left bottom)
				(hide yes)
			)
		)
		(pin "1"
		)
		(instances
			(project "thunderbolt-gpu-adapter"
				(path ""
					(reference "#PWR047")
					(unit 1)
				)
			)
		)
	)
	(symbol
		(lib_id "antmicroCapacitors0402:C_100n_0402")
		(at 44.45 81.28 0)
		(unit 1)
		(exclude_from_sim no)
		(in_bom yes)
		(on_board yes)
		(dnp no)
		(property "Reference" "C104"
			(at 50.165 80.01 0)
			(effects
				(font
					(size 1.27 1.27)
					(thickness 0.15)
				)
			)
		)
		(property "Value" "C_100n_0402"
			(at 64.77 91.44 0)
			(effects
				(font
					(size 1.27 1.27)
					(thickness 0.15)
				)
				(justify left bottom)
				(hide yes)
			)
		)
		(property "Footprint" "antmicro-footprints:C_0402_1005Metric"
			(at 64.77 93.98 0)
			(effects
				(font
					(size 1.27 1.27)
					(thickness 0.15)
				)
				(justify left bottom)
				(hide yes)
			)
		)
		(property "Datasheet" "https://www.murata.com/products/productdetail?partno=GRM155R61H104KE14%23"
			(at 64.77 96.52 0)
			(effects
				(font
					(size 1.27 1.27)
					(thickness 0.15)
				)
				(justify left bottom)
				(hide yes)
			)
		)
		(property "Description" ""
			(at 44.45 81.28 0)
			(effects
				(font
					(size 1.27 1.27)
				)
				(hide yes)
			)
		)
		(property "MPN" "GRM155R61H104KE14D"
			(at 64.77 99.06 0)
			(effects
				(font
					(size 1.27 1.27)
					(thickness 0.15)
				)
				(justify left bottom)
				(hide yes)
			)
		)
		(property "Manufacturer" "Murata"
			(at 64.77 101.6 0)
			(effects
				(font
					(size 1.27 1.27)
					(thickness 0.15)
				)
				(justify left bottom)
				(hide yes)
			)
		)
		(property "License" "Apache-2.0"
			(at 64.77 104.14 0)
			(effects
				(font
					(size 1.27 1.27)
					(thickness 0.15)
				)
				(justify left bottom)
				(hide yes)
			)
		)
		(property "Val" "100n"
			(at 50.165 82.55 0)
			(effects
				(font
					(size 1.27 1.27)
					(thickness 0.15)
				)
			)
		)
		(property "Voltage" "50V"
			(at 64.77 109.22 0)
			(effects
				(font
					(size 1.27 1.27)
				)
				(justify left bottom)
				(hide yes)
			)
		)
		(property "Dielectric" "X5R"
			(at 64.77 111.76 0)
			(effects
				(font
					(size 1.27 1.27)
				)
				(justify left bottom)
				(hide yes)
			)
		)
		(property "Author" "Antmicro"
			(at 64.77 106.68 0)
			(effects
				(font
					(size 1.27 1.27)
					(thickness 0.15)
				)
				(justify left bottom)
				(hide yes)
			)
		)
		(pin "1"
		)
		(pin "2"
		)
		(instances
			(project "thunderbolt-gpu-adapter"
				(path ""
					(reference "C104")
					(unit 1)
				)
			)
		)
	)
	(symbol
		(lib_id "antmicropower:GND")
		(at 111.76 190.5 0)
		(mirror y)
		(unit 1)
		(exclude_from_sim no)
		(in_bom yes)
		(on_board yes)
		(dnp no)
		(property "Reference" "#PWR0132"
			(at 111.76 196.85 0)
			(effects
				(font
					(size 1.27 1.27)
				)
				(hide yes)
			)
		)
		(property "Value" "GND"
			(at 111.76 194.31 0)
			(effects
				(font
					(size 1.27 1.27)
				)
			)
		)
		(property "Footprint" ""
			(at 111.76 190.5 0)
			(effects
				(font
					(size 1.27 1.27)
				)
				(hide yes)
			)
		)
		(property "Datasheet" ""
			(at 111.76 190.5 0)
			(effects
				(font
					(size 1.27 1.27)
				)
				(hide yes)
			)
		)
		(property "Description" ""
			(at 111.76 190.5 0)
			(effects
				(font
					(size 1.27 1.27)
				)
				(hide yes)
			)
		)
		(property "Author" "Antmicro"
			(at 102.87 198.12 0)
			(effects
				(font
					(size 1.27 1.27)
					(thickness 0.15)
				)
				(justify left bottom)
				(hide yes)
			)
		)
		(property "License" "Apache-2.0"
			(at 102.87 200.66 0)
			(effects
				(font
					(size 1.27 1.27)
					(thickness 0.15)
				)
				(justify left bottom)
				(hide yes)
			)
		)
		(pin "1"
		)
		(instances
			(project "thunderbolt-gpu-adapter"
				(path ""
					(reference "#PWR0132")
					(unit 1)
				)
			)
		)
	)
	(symbol
		(lib_id "antmicroResistors0402:R_2k2_0402")
		(at 114.3 240.03 0)
		(unit 1)
		(exclude_from_sim no)
		(in_bom yes)
		(on_board yes)
		(dnp no)
		(property "Reference" "R61"
			(at 116.84 238.125 0)
			(effects
				(font
					(size 1.27 1.27)
					(thickness 0.15)
				)
			)
		)
		(property "Value" "R_2k2_0402"
			(at 134.62 252.73 0)
			(effects
				(font
					(size 1.27 1.27)
					(thickness 0.15)
				)
				(justify left bottom)
				(hide yes)
			)
		)
		(property "Footprint" "antmicro-footprints:R_0402_1005Metric"
			(at 134.62 255.27 0)
			(effects
				(font
					(size 1.27 1.27)
					(thickness 0.15)
				)
				(justify left bottom)
				(hide yes)
			)
		)
		(property "Datasheet" "https://www.bourns.com/docs/product-datasheets/cr.pdf"
			(at 134.62 257.81 0)
			(effects
				(font
					(size 1.27 1.27)
					(thickness 0.15)
				)
				(justify left bottom)
				(hide yes)
			)
		)
		(property "Description" ""
			(at 114.3 240.03 0)
			(effects
				(font
					(size 1.27 1.27)
				)
				(hide yes)
			)
		)
		(property "MPN" "CR0402-FX-2201GLF"
			(at 134.62 260.35 0)
			(effects
				(font
					(size 1.27 1.27)
					(thickness 0.15)
				)
				(justify left bottom)
				(hide yes)
			)
		)
		(property "Manufacturer" "Bourns"
			(at 134.62 262.89 0)
			(effects
				(font
					(size 1.27 1.27)
					(thickness 0.15)
				)
				(justify left bottom)
				(hide yes)
			)
		)
		(property "License" "Apache-2.0"
			(at 134.62 265.43 0)
			(effects
				(font
					(size 1.27 1.27)
					(thickness 0.15)
				)
				(justify left bottom)
				(hide yes)
			)
		)
		(property "Val" "2k2"
			(at 120.65 238.76 0)
			(effects
				(font
					(size 1.27 1.27)
					(thickness 0.15)
				)
			)
		)
		(property "Tolerance" "1%"
			(at 134.62 250.19 0)
			(effects
				(font
					(size 1.27 1.27)
				)
				(justify left bottom)
				(hide yes)
			)
		)
		(property "Author" "Antmicro"
			(at 134.62 267.97 0)
			(effects
				(font
					(size 1.27 1.27)
					(thickness 0.15)
				)
				(justify left bottom)
				(hide yes)
			)
		)
		(pin "1"
		)
		(pin "2"
		)
		(instances
			(project "thunderbolt-gpu-adapter"
				(path ""
					(reference "R61")
					(unit 1)
				)
			)
		)
	)
	(symbol
		(lib_id "antmicroResistors0402:R_499R_0402")
		(at 129.54 104.14 0)
		(unit 1)
		(exclude_from_sim no)
		(in_bom yes)
		(on_board yes)
		(dnp no)
		(fields_autoplaced yes)
		(property "Reference" "R73"
			(at 132.08 107.95 0)
			(effects
				(font
					(size 1.27 1.27)
					(thickness 0.15)
				)
			)
		)
		(property "Value" "R_499R_0402"
			(at 149.86 116.84 0)
			(effects
				(font
					(size 1.27 1.27)
					(thickness 0.15)
				)
				(justify left bottom)
				(hide yes)
			)
		)
		(property "Footprint" "antmicro-footprints:R_0402_1005Metric"
			(at 149.86 119.38 0)
			(effects
				(font
					(size 1.27 1.27)
					(thickness 0.15)
				)
				(justify left bottom)
				(hide yes)
			)
		)
		(property "Datasheet" "https://www.mouser.com/datasheet/2/54/cr-1858361.pdf"
			(at 149.86 121.92 0)
			(effects
				(font
					(size 1.27 1.27)
					(thickness 0.15)
				)
				(justify left bottom)
				(hide yes)
			)
		)
		(property "Description" ""
			(at 129.54 104.14 0)
			(effects
				(font
					(size 1.27 1.27)
				)
				(hide yes)
			)
		)
		(property "MPN" "CR0402-FX-4990GLF"
			(at 149.86 124.46 0)
			(effects
				(font
					(size 1.27 1.27)
					(thickness 0.15)
				)
				(justify left bottom)
				(hide yes)
			)
		)
		(property "Manufacturer" "Bourns"
			(at 149.86 127 0)
			(effects
				(font
					(size 1.27 1.27)
					(thickness 0.15)
				)
				(justify left bottom)
				(hide yes)
			)
		)
		(property "License" "Apache-2.0"
			(at 149.86 129.54 0)
			(effects
				(font
					(size 1.27 1.27)
					(thickness 0.15)
				)
				(justify left bottom)
				(hide yes)
			)
		)
		(property "Val" "499R"
			(at 132.08 110.49 0)
			(effects
				(font
					(size 1.27 1.27)
					(thickness 0.15)
				)
			)
		)
		(property "Tolerance" "1%"
			(at 149.86 114.3 0)
			(effects
				(font
					(size 1.27 1.27)
				)
				(justify left bottom)
				(hide yes)
			)
		)
		(property "Author" "Antmicro"
			(at 149.86 132.08 0)
			(effects
				(font
					(size 1.27 1.27)
					(thickness 0.15)
				)
				(justify left bottom)
				(hide yes)
			)
		)
		(pin "1"
		)
		(pin "2"
		)
		(instances
			(project "thunderbolt-gpu-adapter"
				(path ""
					(reference "R73")
					(unit 1)
				)
			)
		)
	)
	(symbol
		(lib_id "antmicroResistors0402:R_2k2_0402")
		(at 114.3 189.23 0)
		(unit 1)
		(exclude_from_sim no)
		(in_bom yes)
		(on_board yes)
		(dnp no)
		(property "Reference" "R59"
			(at 116.84 191.135 0)
			(effects
				(font
					(size 1.27 1.27)
					(thickness 0.15)
				)
			)
		)
		(property "Value" "R_2k2_0402"
			(at 134.62 201.93 0)
			(effects
				(font
					(size 1.27 1.27)
					(thickness 0.15)
				)
				(justify left bottom)
				(hide yes)
			)
		)
		(property "Footprint" "antmicro-footprints:R_0402_1005Metric"
			(at 134.62 204.47 0)
			(effects
				(font
					(size 1.27 1.27)
					(thickness 0.15)
				)
				(justify left bottom)
				(hide yes)
			)
		)
		(property "Datasheet" "https://www.bourns.com/docs/product-datasheets/cr.pdf"
			(at 134.62 207.01 0)
			(effects
				(font
					(size 1.27 1.27)
					(thickness 0.15)
				)
				(justify left bottom)
				(hide yes)
			)
		)
		(property "Description" ""
			(at 114.3 189.23 0)
			(effects
				(font
					(size 1.27 1.27)
				)
				(hide yes)
			)
		)
		(property "MPN" "CR0402-FX-2201GLF"
			(at 134.62 209.55 0)
			(effects
				(font
					(size 1.27 1.27)
					(thickness 0.15)
				)
				(justify left bottom)
				(hide yes)
			)
		)
		(property "Manufacturer" "Bourns"
			(at 134.62 212.09 0)
			(effects
				(font
					(size 1.27 1.27)
					(thickness 0.15)
				)
				(justify left bottom)
				(hide yes)
			)
		)
		(property "License" "Apache-2.0"
			(at 134.62 214.63 0)
			(effects
				(font
					(size 1.27 1.27)
					(thickness 0.15)
				)
				(justify left bottom)
				(hide yes)
			)
		)
		(property "Val" "2k2"
			(at 120.65 190.5 0)
			(effects
				(font
					(size 1.27 1.27)
					(thickness 0.15)
				)
			)
		)
		(property "Tolerance" "1%"
			(at 134.62 199.39 0)
			(effects
				(font
					(size 1.27 1.27)
				)
				(justify left bottom)
				(hide yes)
			)
		)
		(property "Author" "Antmicro"
			(at 134.62 217.17 0)
			(effects
				(font
					(size 1.27 1.27)
					(thickness 0.15)
				)
				(justify left bottom)
				(hide yes)
			)
		)
		(pin "1"
		)
		(pin "2"
		)
		(instances
			(project "thunderbolt-gpu-adapter"
				(path ""
					(reference "R59")
					(unit 1)
				)
			)
		)
	)
)
